FILE_TYPE = MACRO_DRAWING;
SET COLOR_WIRE YELLOW;
SET COLOR_PROP MONO;
SET COLOR_DOT WHITE;
SET COLOR_ARC YELLOW;
SET COLOR_BODY GREEN;
SET COLOR_NOTE MONO;
SET PROP_DISPLAY VALUE;
SET PAGE_NUMBER P196;
FORCEADD CAP_A..1
(-2200 4500);
FORCEPROP 1 LASTPIN (-2200 4400) $PN 2
J 0
(-2190 4380);
DISPLAY 0.617021 (-2190 4380);
PAINT ORANGE (-2190 4380);
FORCEPROP 1 LASTPIN (-2200 4600) $PN 1
J 0
(-2190 4580);
DISPLAY 0.617021 (-2190 4580);
PAINT ORANGE (-2190 4580);
FORCEPROP 1 LAST MATERIAL X6S
J 0
(-2150 4400);
DISPLAY 0.617021 (-2150 4400);
PAINT SKYBLUE (-2150 4400);
FORCEPROP 1 LAST TOLERANCE 10%
J 0
(-2150 4450);
DISPLAY 0.617021 (-2150 4450);
PAINT SKYBLUE (-2150 4450);
FORCEPROP 2 LAST NO_XNET_CONNECTION 1
J 0
(-2150 4700);
PAINT MONO (-2150 4700);
FORCEPROP 1 LAST VOLTAGE 6.3V
J 0
(-2150 4500);
DISPLAY 0.617021 (-2150 4500);
PAINT SKYBLUE (-2150 4500);
FORCEPROP 1 LAST PACK_TYPE 0402V
J 0
(-2150 4300);
DISPLAY 0.617021 (-2150 4300);
PAINT SKYBLUE (-2150 4300);
FORCEPROP 1 LAST VALUE 1.0UF
J 0
(-2150 4550);
DISPLAY 0.617021 (-2150 4550);
PAINT SKYBLUE (-2150 4550);
FORCEPROP 1 LAST PART_NUMBER D97712-004
J 0
(-2150 4350);
DISPLAY 0.617021 (-2150 4350);
PAINT BLUE (-2150 4350);
FORCEPROP 1 LAST LOCATION C2U26
J 0
(-2150 4600);
DISPLAY 0.617021 (-2150 4600);
PAINT AQUA (-2150 4600);
FORCEPROP 2 LAST CDS_LIB dev_discrete
J 0
(-2200 4500);
PAINT ORANGE (-2200 4500);
DISPLAY INVISIBLE (-2200 4500);
FORCEPROP 2 LAST CDS_LOCATION C2U26
J 0
(-2150 4600);
DISPLAY 0.617021 (-2150 4600);
PAINT AQUA (-2150 4600);
DISPLAY INVISIBLE (-2150 4600);
FORCEPROP 1 LAST PATH I102
J 0
(-2150 4650);
DISPLAY 0.978723 (-2150 4650);
PAINT WHITE (-2150 4650);
DISPLAY INVISIBLE (-2150 4650);
FORCEPROP 2 LAST SEC 1
J 0
(-2150 4700);
DISPLAY 0.680851 (-2150 4700);
PAINT MONO (-2150 4700);
DISPLAY INVISIBLE (-2150 4700);
FORCEPROP 2 LAST BOM_COST SB
J 0
(-2150 4650);
DISPLAY 1.659574 (-2150 4650);
PAINT WHITE (-2150 4650);
DISPLAY INVISIBLE (-2150 4650);
FORCEPROP 2 LAST CDS_SEC 1
J 0
(-2150 4750);
PAINT ORANGE (-2150 4750);
DISPLAY INVISIBLE (-2150 4750);
FORCEPROP 2 LAST ROOM SB_VRD
J 0
(-2150 4650);
DISPLAY 1.659574 (-2150 4650);
PAINT WHITE (-2150 4650);
DISPLAY INVISIBLE (-2150 4650);
FORCEPROP 2 LAST SEC_TYPE 0402V
J 0
(-2150 4700);
DISPLAY 1.021277 (-2150 4700);
PAINT ORANGE (-2150 4700);
DISPLAY INVISIBLE (-2150 4700);
FORCEADD DIODE..3
(825 3650);
FORCEPROP 1 LAST PACK_TYPE SMLF
J 0
(800 3410);
DISPLAY 0.617021 (800 3410);
PAINT SKYBLUE (800 3410);
FORCEPROP 1 LAST VALUE BAT54WS
J 0
(800 3525);
DISPLAY 0.617021 (800 3525);
PAINT SKYBLUE (800 3525);
FORCEPROP 1 LAST MATERIAL IC
J 0
(800 3472);
DISPLAY 0.617021 (800 3472);
PAINT SKYBLUE (800 3472);
FORCEPROP 1 LASTPIN (725 3650) $PN 1
J 2
(760 3660);
DISPLAY 0.617021 (760 3660);
PAINT AQUA (760 3660);
FORCEPROP 1 LAST LOCATION CR7E1
J 0
(798 3806);
DISPLAY 0.617021 (798 3806);
PAINT AQUA (798 3806);
FORCEPROP 1 LASTPIN (925 3650) $PN 2
J 0
(900 3660);
DISPLAY 0.617021 (900 3660);
PAINT AQUA (900 3660);
FORCEPROP 1 LAST PART_NUMBER C73510-001
J 0
(800 3750);
DISPLAY 0.617021 (800 3750);
PAINT BLUE (800 3750);
FORCEPROP 1 LAST PATH I103
J 0
(805 3860);
DISPLAY 0.978723 (805 3860);
PAINT PINK (805 3860);
DISPLAY INVISIBLE (805 3860);
FORCEPROP 2 LAST CDS_LOCATION CR7E1
J 0
(798 3806);
DISPLAY 0.617021 (798 3806);
PAINT AQUA (798 3806);
DISPLAY INVISIBLE (798 3806);
FORCEPROP 2 LAST SEC 1
J 0
(825 3925);
PAINT MONO (825 3925);
DISPLAY INVISIBLE (825 3925);
FORCEPROP 2 LAST SEC_TYPE SMLF
J 0
(825 3925);
DISPLAY 1.021277 (825 3925);
PAINT ORANGE (825 3925);
DISPLAY INVISIBLE (825 3925);
FORCEPROP 2 LAST CDS_LIB mstr_discrete
J 0
(825 3650);
PAINT ORANGE (825 3650);
DISPLAY INVISIBLE (825 3650);
FORCEADD TPS3700..1
(-500 2300);
FORCEPROP 2 LASTPIN (-800 2250) $PN 4
J 2
(-810 2260);
DISPLAY 0.617021 (-810 2260);
PAINT MONO (-810 2260);
FORCEPROP 2 LASTPIN (-800 2150) $PN 3
J 2
(-810 2160);
DISPLAY 0.617021 (-810 2160);
PAINT MONO (-810 2160);
FORCEPROP 2 LASTPIN (-800 2400) $PN 2
J 2
(-810 2410);
DISPLAY 0.617021 (-810 2410);
PAINT MONO (-810 2410);
FORCEPROP 1 LAST MATERIAL IC
J 0
(-750 2550);
DISPLAY 0.617021 (-750 2550);
PAINT SKYBLUE (-750 2550);
FORCEPROP 1 LAST LOCATION U8D8
J 0
(-750 2600);
DISPLAY 0.617021 (-750 2600);
PAINT AQUA (-750 2600);
FORCEPROP 1 LAST PART_NUMBER H69492-001
J 0
(-750 2050);
DISPLAY 0.617021 (-750 2050);
PAINT BLUE (-750 2050);
FORCEPROP 2 LASTPIN (-200 2150) $PN 5
J 0
(-190 2160);
DISPLAY 0.617021 (-190 2160);
PAINT MONO (-190 2160);
FORCEPROP 2 LASTPIN (-200 2300) $PN 1
J 0
(-190 2310);
DISPLAY 0.617021 (-190 2310);
PAINT MONO (-190 2310);
FORCEPROP 2 LASTPIN (-200 2400) $PN 6
J 0
(-190 2410);
DISPLAY 0.617021 (-190 2410);
PAINT MONO (-190 2410);
FORCEPROP 2 LAST ROOM V_SUPER
J 0
(-750 2650);
DISPLAY 1.021277 (-750 2650);
PAINT ORANGE (-750 2650);
DISPLAY INVISIBLE (-750 2650);
FORCEPROP 2 LAST $SEC 1
J 0
(-750 2650);
PAINT MONO (-750 2650);
DISPLAY INVISIBLE (-750 2650);
FORCEPROP 2 LAST CDS_SEC 1
J 0
(-750 2650);
PAINT MONO (-750 2650);
DISPLAY INVISIBLE (-750 2650);
FORCEPROP 1 LAST PACK_TYPE SM
J 0
(-750 2650);
PAINT SKYBLUE (-750 2650);
DISPLAY INVISIBLE (-750 2650);
FORCEPROP 2 LAST CDS_LIB mstr_vreg
J 0
(-500 2300);
PAINT ORANGE (-500 2300);
DISPLAY INVISIBLE (-500 2300);
FORCEPROP 1 LAST CDS_LMAN_SYM_OUTLINE -250,200,250,-200
J 0
(-500 2300);
DISPLAY 0.468085 (-500 2300);
PAINT GREEN (-500 2300);
DISPLAY INVISIBLE (-500 2300);
FORCEPROP 1 LAST PATH I104
J 0
(-500 2550);
PAINT GREEN (-500 2550);
DISPLAY INVISIBLE (-500 2550);
FORCEADD CAP_A..1
(-1000 1950);
FORCEPROP 1 LAST PACK_TYPE 0402V
J 0
(-950 1750);
DISPLAY 0.617021 (-950 1750);
PAINT SKYBLUE (-950 1750);
FORCEPROP 1 LAST MATERIAL X7R
J 0
(-950 1850);
DISPLAY 0.617021 (-950 1850);
PAINT SKYBLUE (-950 1850);
FORCEPROP 1 LAST VOLTAGE 16V
J 0
(-950 1950);
DISPLAY 0.617021 (-950 1950);
PAINT SKYBLUE (-950 1950);
FORCEPROP 1 LAST TOLERANCE 10%
J 0
(-950 1900);
DISPLAY 0.617021 (-950 1900);
PAINT SKYBLUE (-950 1900);
FORCEPROP 1 LAST VALUE 0.1UF
J 0
(-950 2000);
DISPLAY 0.617021 (-950 2000);
PAINT SKYBLUE (-950 2000);
FORCEPROP 1 LAST PART_NUMBER A36096-030
J 0
(-950 1800);
DISPLAY 0.617021 (-950 1800);
PAINT BLUE (-950 1800);
FORCEPROP 1 LAST LOCATION C8D4
J 0
(-950 2050);
DISPLAY 0.617021 (-950 2050);
PAINT AQUA (-950 2050);
FORCEPROP 2 LAST CDS_LIB dev_discrete
J 0
(-1000 1950);
PAINT ORANGE (-1000 1950);
DISPLAY INVISIBLE (-1000 1950);
FORCEPROP 1 LASTPIN (-1000 1850) $PN 2
J 0
(-990 1830);
DISPLAY 0.787234 (-990 1830);
PAINT ORANGE (-990 1830);
DISPLAY INVISIBLE (-990 1830);
FORCEPROP 1 LASTPIN (-1000 2050) $PN 1
J 0
(-990 2030);
DISPLAY 0.787234 (-990 2030);
PAINT ORANGE (-990 2030);
DISPLAY INVISIBLE (-990 2030);
FORCEPROP 2 LAST ROOM V_SUPER
J 0
(-950 2100);
DISPLAY 1.021277 (-950 2100);
PAINT ORANGE (-950 2100);
DISPLAY INVISIBLE (-950 2100);
FORCEPROP 1 LAST PATH I105
J 0
(-950 2100);
DISPLAY 0.978723 (-950 2100);
PAINT WHITE (-950 2100);
DISPLAY INVISIBLE (-950 2100);
FORCEADD RES..1
(1350 2400);
FORCEPROP 1 LASTPIN (1250 2400) $PN 1
J 0
(1262 2412);
DISPLAY 0.617021 (1262 2412);
PAINT ORANGE (1262 2412);
FORCEPROP 1 LAST WATTAGE 1/16W
J 2
(1325 2250);
DISPLAY 0.617021 (1325 2250);
PAINT SKYBLUE (1325 2250);
FORCEPROP 1 LAST VALUE 100.0
J 2
(1325 2300);
DISPLAY 0.617021 (1325 2300);
PAINT SKYBLUE (1325 2300);
FORCEPROP 1 LAST MATERIAL CHIP
J 0
(1350 2250);
DISPLAY 0.617021 (1350 2250);
PAINT SKYBLUE (1350 2250);
FORCEPROP 1 LAST TOLERANCE 1%
J 0
(1350 2300);
DISPLAY 0.617021 (1350 2300);
PAINT SKYBLUE (1350 2300);
FORCEPROP 1 LASTPIN (1450 2400) $PN 2
J 0
(1412 2412);
DISPLAY 0.617021 (1412 2412);
PAINT ORANGE (1412 2412);
FORCEPROP 1 LAST LOCATION R8D42
J 0
(1300 2450);
DISPLAY 0.617021 (1300 2450);
PAINT AQUA (1300 2450);
FORCEPROP 1 LAST PART_NUMBER G21796-017
J 0
(1300 2500);
DISPLAY 0.617021 (1300 2500);
PAINT BLUE (1300 2500);
FORCEPROP 1 LAST PACK_TYPE 0402
J 0
(1600 2250);
DISPLAY 0.617021 (1600 2250);
PAINT SKYBLUE (1600 2250);
FORCEPROP 2 LAST CDS_LIB mstr_discrete
J 0
(1350 2400);
PAINT ORANGE (1350 2400);
DISPLAY INVISIBLE (1350 2400);
FORCEPROP 1 LAST PATH I106
J 0
(1300 2550);
DISPLAY 0.978723 (1300 2550);
PAINT WHITE (1300 2550);
DISPLAY INVISIBLE (1300 2550);
FORCEPROP 0 LAST ROOM V_SUPER
J 0
(1300 2600);
DISPLAY 1.021277 (1300 2600);
PAINT ORANGE (1300 2600);
DISPLAY INVISIBLE (1300 2600);
FORCEPROP 2 LAST SEC_TYPE 0402
J 0
(1300 2600);
DISPLAY 1.021277 (1300 2600);
PAINT ORANGE (1300 2600);
DISPLAY INVISIBLE (1300 2600);
FORCEPROP 2 LAST SEC 1
J 0
(1300 2600);
PAINT MONO (1300 2600);
DISPLAY INVISIBLE (1300 2600);
FORCEADD OFFPAGE..2
(1850 2400);
FORCEPROP 2 LAST $XR0 191 
J 0
(2039 2400);
DISPLAY 0.638298 (2039 2400);
PAINT MONO (2039 2400);
FORCEPROP 2 LASTPIN (1800 2400) SIG_NAME PWRGD_P12V_MAIN
J 2
(1790 2410);
DISPLAY 0.617021 (1790 2410);
PAINT ORANGE (1790 2410);
FORCEPROP 2 LAST CDS_LIB mstr_standard
J 0
(1850 2400);
PAINT ORANGE (1850 2400);
DISPLAY INVISIBLE (1850 2400);
FORCEPROP 1 LAST COMMENT_BODY TRUE
J 0
(1805 2305);
DISPLAY 0.872340 (1805 2305);
PAINT GREEN (1805 2305);
DISPLAY INVISIBLE (1805 2305);
FORCEPROP 2 LAST PATH I107
J 0
(2025 2475);
DISPLAY 1.021277 (2025 2475);
PAINT ORANGE (2025 2475);
DISPLAY INVISIBLE (2025 2475);
FORCEPROP 1 LAST OFFPAGE TRUE
J 0
(2175 2275);
DISPLAY 0.872340 (2175 2275);
PAINT GREEN (2175 2275);
DISPLAY INVISIBLE (2175 2275);
FORCEADD GND..1
(-150 2000);
FORCEPROP 3 LASTPIN (-150 2050) SIG_NAME GND\g
J 0
(-140 2060);
DISPLAY 0.659574 (-140 2060);
PAINT MONO (-140 2060);
DISPLAY INVISIBLE (-140 2060);
FORCEPROP 1 LAST PATH I108
J 0
(-75 2000);
DISPLAY 0.872340 (-75 2000);
PAINT AQUA (-75 2000);
DISPLAY INVISIBLE (-75 2000);
FORCEPROP 1 LAST BODY_TYPE PLUMBING
J 0
(-195 1957);
DISPLAY 0.340426 (-195 1957);
PAINT GREEN (-195 1957);
DISPLAY INVISIBLE (-195 1957);
FORCEPROP 2 LAST CDS_LIB mstr_symbols
J 0
(-150 2000);
PAINT ORANGE (-150 2000);
DISPLAY INVISIBLE (-150 2000);
FORCEPROP 1 LAST SIZE 1B
J 0
(-75 1950);
DISPLAY 0.872340 (-75 1950);
PAINT AQUA (-75 1950);
DISPLAY INVISIBLE (-75 1950);
FORCEPROP 1 LAST VOLTAGE 0.0V
J 0
(-195 1957);
DISPLAY 0.340426 (-195 1957);
PAINT SKYBLUE (-195 1957);
DISPLAY INVISIBLE (-195 1957);
FORCEPROP 1 LAST HDL_POWER GND
J 0
(-150 2150);
DISPLAY 0.872340 (-150 2150);
PAINT GREEN (-150 2150);
DISPLAY INVISIBLE (-150 2150);
FORCEADD GND..1
(-1000 1750);
FORCEPROP 3 LASTPIN (-1000 1800) SIG_NAME GND\g
J 0
(-990 1810);
DISPLAY 0.659574 (-990 1810);
PAINT MONO (-990 1810);
DISPLAY INVISIBLE (-990 1810);
FORCEPROP 1 LAST BODY_TYPE PLUMBING
J 0
(-1045 1707);
DISPLAY 0.340426 (-1045 1707);
PAINT GREEN (-1045 1707);
DISPLAY INVISIBLE (-1045 1707);
FORCEPROP 1 LAST VOLTAGE 0.0V
J 0
(-1045 1707);
DISPLAY 0.340426 (-1045 1707);
PAINT SKYBLUE (-1045 1707);
DISPLAY INVISIBLE (-1045 1707);
FORCEPROP 2 LAST CDS_LIB mstr_symbols
J 0
(-1000 1750);
PAINT ORANGE (-1000 1750);
DISPLAY INVISIBLE (-1000 1750);
FORCEPROP 1 LAST SIZE 1B
J 0
(-925 1700);
DISPLAY 0.872340 (-925 1700);
PAINT AQUA (-925 1700);
DISPLAY INVISIBLE (-925 1700);
FORCEPROP 1 LAST PATH I110
J 0
(-925 1750);
DISPLAY 0.872340 (-925 1750);
PAINT AQUA (-925 1750);
DISPLAY INVISIBLE (-925 1750);
FORCEPROP 1 LAST HDL_POWER GND
J 0
(-1000 1900);
DISPLAY 0.872340 (-1000 1900);
PAINT GREEN (-1000 1900);
DISPLAY INVISIBLE (-1000 1900);
FORCEADD P3V3_STBY..1
(-1000 2750);
FORCEPROP 3 LASTPIN (-1000 2700) SIG_NAME P3V3_STBY\g
J 0
(-990 2710);
DISPLAY 0.659574 (-990 2710);
PAINT MONO (-990 2710);
DISPLAY INVISIBLE (-990 2710);
FORCEPROP 1 LAST HDL_POWER P3V3_STBY
J 0
(-1300 2625);
DISPLAY 0.872340 (-1300 2625);
PAINT ORANGE (-1300 2625);
DISPLAY INVISIBLE (-1300 2625);
FORCEPROP 1 LAST BODY_TYPE PLUMBING
J 0
(-1045 2707);
DISPLAY 0.340426 (-1045 2707);
PAINT GREEN (-1045 2707);
DISPLAY INVISIBLE (-1045 2707);
FORCEPROP 1 LAST VOLTAGE 3.3V
J 0
(-1045 2707);
DISPLAY 0.340426 (-1045 2707);
PAINT SKYBLUE (-1045 2707);
DISPLAY INVISIBLE (-1045 2707);
FORCEPROP 1 LAST PATH I111
J 0
(-955 2752);
DISPLAY 0.340426 (-955 2752);
PAINT GREEN (-955 2752);
DISPLAY INVISIBLE (-955 2752);
FORCEPROP 1 LAST SIZE 1B
J 0
(-955 2772);
DISPLAY 0.340426 (-955 2772);
PAINT GREEN (-955 2772);
DISPLAY INVISIBLE (-955 2772);
FORCEPROP 2 LAST CDS_LIB mstr_symbols
J 0
(-1000 2750);
PAINT ORANGE (-1000 2750);
DISPLAY INVISIBLE (-1000 2750);
FORCEADD RES..2
(-1750 2800);
FORCEPROP 1 LASTPIN (-1750 2700) $PN 2
J 0
(-1745 2710);
DISPLAY 0.617021 (-1745 2710);
PAINT ORANGE (-1745 2710);
FORCEPROP 1 LAST PACK_TYPE 0402
J 0
(-1710 2625);
DISPLAY 0.617021 (-1710 2625);
PAINT SKYBLUE (-1710 2625);
FORCEPROP 1 LAST MATERIAL CHIP
J 0
(-1710 2725);
DISPLAY 0.617021 (-1710 2725);
PAINT SKYBLUE (-1710 2725);
FORCEPROP 1 LAST WATTAGE 1/16W
J 0
(-1710 2775);
DISPLAY 0.617021 (-1710 2775);
PAINT SKYBLUE (-1710 2775);
FORCEPROP 1 LASTPIN (-1750 2900) $PN 1
J 0
(-1745 2862);
DISPLAY 0.617021 (-1745 2862);
PAINT ORANGE (-1745 2862);
FORCEPROP 1 LAST TOLERANCE 1%
J 0
(-1705 2825);
DISPLAY 0.617021 (-1705 2825);
PAINT SKYBLUE (-1705 2825);
FORCEPROP 1 LAST LOCATION R8D38
J 0
(-1705 2925);
DISPLAY 0.617021 (-1705 2925);
PAINT AQUA (-1705 2925);
FORCEPROP 1 LAST VALUE 100.0K
J 0
(-1705 2875);
DISPLAY 0.617021 (-1705 2875);
PAINT SKYBLUE (-1705 2875);
FORCEPROP 1 LAST PART_NUMBER G21796-010
J 0
(-1710 2675);
DISPLAY 0.617021 (-1710 2675);
PAINT BLUE (-1710 2675);
FORCEPROP 2 LAST CDS_LIB mstr_discrete
J 0
(-1750 2800);
PAINT ORANGE (-1750 2800);
DISPLAY INVISIBLE (-1750 2800);
FORCEPROP 2 LAST ROOM V_SUPER
J 0
(-1700 2975);
DISPLAY 1.021277 (-1700 2975);
PAINT ORANGE (-1700 2975);
DISPLAY INVISIBLE (-1700 2975);
FORCEPROP 1 LAST PATH I112
J 0
(-1700 2975);
DISPLAY 0.978723 (-1700 2975);
PAINT WHITE (-1700 2975);
DISPLAY INVISIBLE (-1700 2975);
FORCEPROP 2 LAST SEC_TYPE 0402
J 0
(-1700 3025);
DISPLAY 1.021277 (-1700 3025);
PAINT ORANGE (-1700 3025);
DISPLAY INVISIBLE (-1700 3025);
FORCEPROP 2 LAST SEC 1
J 0
(-1700 3025);
PAINT MONO (-1700 3025);
DISPLAY INVISIBLE (-1700 3025);
FORCEADD RES..2
(-1750 2400);
FORCEPROP 1 LAST PACK_TYPE 0402
J 0
(-1710 2225);
DISPLAY 0.617021 (-1710 2225);
PAINT SKYBLUE (-1710 2225);
FORCEPROP 1 LASTPIN (-1750 2500) $PN 1
J 0
(-1745 2462);
DISPLAY 0.617021 (-1745 2462);
PAINT ORANGE (-1745 2462);
FORCEPROP 1 LASTPIN (-1750 2300) $PN 2
J 0
(-1745 2310);
DISPLAY 0.617021 (-1745 2310);
PAINT ORANGE (-1745 2310);
FORCEPROP 1 LAST VALUE 3.74K
J 0
(-1705 2475);
DISPLAY 0.617021 (-1705 2475);
PAINT SKYBLUE (-1705 2475);
FORCEPROP 1 LAST TOLERANCE 1%
J 0
(-1705 2425);
DISPLAY 0.617021 (-1705 2425);
PAINT SKYBLUE (-1705 2425);
FORCEPROP 1 LAST MATERIAL CHIP
J 0
(-1710 2325);
DISPLAY 0.617021 (-1710 2325);
PAINT SKYBLUE (-1710 2325);
FORCEPROP 1 LAST WATTAGE 1/16W
J 0
(-1710 2375);
DISPLAY 0.617021 (-1710 2375);
PAINT SKYBLUE (-1710 2375);
FORCEPROP 1 LAST LOCATION R8D40
J 0
(-1705 2525);
DISPLAY 0.617021 (-1705 2525);
PAINT AQUA (-1705 2525);
FORCEPROP 1 LAST PART_NUMBER G21796-059
J 0
(-1710 2275);
DISPLAY 0.617021 (-1710 2275);
PAINT BLUE (-1710 2275);
FORCEPROP 2 LAST CDS_LIB mstr_discrete
J 0
(-1750 2400);
PAINT ORANGE (-1750 2400);
DISPLAY INVISIBLE (-1750 2400);
FORCEPROP 2 LAST ROOM V_SUPER
J 0
(-1700 2575);
DISPLAY 1.021277 (-1700 2575);
PAINT ORANGE (-1700 2575);
DISPLAY INVISIBLE (-1700 2575);
FORCEPROP 1 LAST PATH I113
J 0
(-1700 2575);
DISPLAY 0.978723 (-1700 2575);
PAINT WHITE (-1700 2575);
DISPLAY INVISIBLE (-1700 2575);
FORCEPROP 2 LAST SEC_TYPE 0402
J 0
(-1700 2625);
DISPLAY 1.021277 (-1700 2625);
PAINT ORANGE (-1700 2625);
DISPLAY INVISIBLE (-1700 2625);
FORCEPROP 2 LAST SEC 1
J 0
(-1700 2625);
PAINT MONO (-1700 2625);
DISPLAY INVISIBLE (-1700 2625);
FORCEADD RES..2
(-1750 1850);
FORCEPROP 1 LASTPIN (-1750 1750) $PN 2
J 0
(-1745 1760);
DISPLAY 0.617021 (-1745 1760);
PAINT ORANGE (-1745 1760);
FORCEPROP 1 LAST PACK_TYPE 0402
J 0
(-1710 1675);
DISPLAY 0.617021 (-1710 1675);
PAINT SKYBLUE (-1710 1675);
FORCEPROP 1 LAST MATERIAL CHIP
J 0
(-1710 1775);
DISPLAY 0.617021 (-1710 1775);
PAINT SKYBLUE (-1710 1775);
FORCEPROP 1 LASTPIN (-1750 1950) $PN 1
J 0
(-1745 1912);
DISPLAY 0.617021 (-1745 1912);
PAINT ORANGE (-1745 1912);
FORCEPROP 1 LAST LOCATION R8D39
J 0
(-1705 1975);
DISPLAY 0.617021 (-1705 1975);
PAINT AQUA (-1705 1975);
FORCEPROP 1 LAST VALUE 49.9K
J 0
(-1705 1925);
DISPLAY 0.617021 (-1705 1925);
PAINT SKYBLUE (-1705 1925);
FORCEPROP 1 LAST TOLERANCE 1%
J 0
(-1705 1875);
DISPLAY 0.617021 (-1705 1875);
PAINT SKYBLUE (-1705 1875);
FORCEPROP 1 LAST WATTAGE 1/16W
J 0
(-1710 1825);
DISPLAY 0.617021 (-1710 1825);
PAINT SKYBLUE (-1710 1825);
FORCEPROP 1 LAST PART_NUMBER G21796-048
J 0
(-1710 1725);
DISPLAY 0.617021 (-1710 1725);
PAINT BLUE (-1710 1725);
FORCEPROP 2 LAST CDS_LIB mstr_discrete
J 0
(-1750 1850);
PAINT ORANGE (-1750 1850);
DISPLAY INVISIBLE (-1750 1850);
FORCEPROP 2 LAST ROOM V_SUPER
J 0
(-1700 2025);
DISPLAY 1.021277 (-1700 2025);
PAINT ORANGE (-1700 2025);
DISPLAY INVISIBLE (-1700 2025);
FORCEPROP 1 LAST PATH I114
J 0
(-1700 2025);
DISPLAY 0.978723 (-1700 2025);
PAINT WHITE (-1700 2025);
DISPLAY INVISIBLE (-1700 2025);
FORCEPROP 2 LAST SEC_TYPE 0402
J 0
(-1700 2075);
DISPLAY 1.021277 (-1700 2075);
PAINT ORANGE (-1700 2075);
DISPLAY INVISIBLE (-1700 2075);
FORCEPROP 2 LAST SEC 1
J 0
(-1700 2075);
PAINT MONO (-1700 2075);
DISPLAY INVISIBLE (-1700 2075);
FORCEADD RES..2
(-1750 1450);
FORCEPROP 1 LAST PACK_TYPE 0402
J 0
(-1710 1275);
DISPLAY 0.617021 (-1710 1275);
PAINT SKYBLUE (-1710 1275);
FORCEPROP 1 LASTPIN (-1750 1350) $PN 2
J 0
(-1745 1360);
DISPLAY 0.617021 (-1745 1360);
PAINT ORANGE (-1745 1360);
FORCEPROP 1 LAST TOLERANCE 1%
J 0
(-1705 1475);
DISPLAY 0.617021 (-1705 1475);
PAINT SKYBLUE (-1705 1475);
FORCEPROP 1 LAST MATERIAL CHIP
J 0
(-1710 1375);
DISPLAY 0.617021 (-1710 1375);
PAINT SKYBLUE (-1710 1375);
FORCEPROP 1 LAST WATTAGE 1/16W
J 0
(-1710 1425);
DISPLAY 0.617021 (-1710 1425);
PAINT SKYBLUE (-1710 1425);
FORCEPROP 1 LASTPIN (-1750 1550) $PN 1
J 0
(-1745 1512);
DISPLAY 0.617021 (-1745 1512);
PAINT ORANGE (-1745 1512);
FORCEPROP 1 LAST VALUE 4.75K
J 0
(-1705 1525);
DISPLAY 0.617021 (-1705 1525);
PAINT SKYBLUE (-1705 1525);
FORCEPROP 1 LAST LOCATION R8D37
J 0
(-1705 1575);
DISPLAY 0.617021 (-1705 1575);
PAINT AQUA (-1705 1575);
FORCEPROP 1 LAST PART_NUMBER G21796-072
J 0
(-1710 1325);
DISPLAY 0.617021 (-1710 1325);
PAINT BLUE (-1710 1325);
FORCEPROP 2 LAST CDS_LIB mstr_discrete
J 0
(-1750 1450);
PAINT ORANGE (-1750 1450);
DISPLAY INVISIBLE (-1750 1450);
FORCEPROP 2 LAST ROOM V_SUPER
J 0
(-1700 1625);
DISPLAY 1.021277 (-1700 1625);
PAINT ORANGE (-1700 1625);
DISPLAY INVISIBLE (-1700 1625);
FORCEPROP 1 LAST PATH I115
J 0
(-1700 1625);
DISPLAY 0.978723 (-1700 1625);
PAINT WHITE (-1700 1625);
DISPLAY INVISIBLE (-1700 1625);
FORCEPROP 2 LAST SEC_TYPE 0402
J 0
(-1700 1675);
DISPLAY 1.021277 (-1700 1675);
PAINT ORANGE (-1700 1675);
DISPLAY INVISIBLE (-1700 1675);
FORCEPROP 2 LAST SEC 1
J 0
(-1700 1675);
PAINT MONO (-1700 1675);
DISPLAY INVISIBLE (-1700 1675);
FORCEADD P5V..1
(-1750 2050);
FORCEPROP 3 LASTPIN (-1750 2000) SIG_NAME P5V\g
J 0
(-1740 2010);
DISPLAY 0.659574 (-1740 2010);
PAINT MONO (-1740 2010);
DISPLAY INVISIBLE (-1740 2010);
FORCEPROP 1 LAST HDL_POWER P5V
J 0
(-2050 1925);
DISPLAY 0.872340 (-2050 1925);
PAINT ORANGE (-2050 1925);
DISPLAY INVISIBLE (-2050 1925);
FORCEPROP 1 LAST BODY_TYPE PLUMBING
J 0
(-1795 2007);
DISPLAY 0.340426 (-1795 2007);
PAINT GREEN (-1795 2007);
DISPLAY INVISIBLE (-1795 2007);
FORCEPROP 1 LAST VOLTAGE 5.0V
J 0
(-1795 2007);
DISPLAY 0.340426 (-1795 2007);
PAINT SKYBLUE (-1795 2007);
DISPLAY INVISIBLE (-1795 2007);
FORCEPROP 1 LAST PATH I116
J 0
(-1705 2052);
DISPLAY 0.340426 (-1705 2052);
PAINT GREEN (-1705 2052);
DISPLAY INVISIBLE (-1705 2052);
FORCEPROP 2 LAST CDS_LIB mstr_symbols
J 0
(-1750 2050);
PAINT ORANGE (-1750 2050);
DISPLAY INVISIBLE (-1750 2050);
FORCEPROP 1 LAST SIZE 1B
J 0
(-1705 2072);
DISPLAY 0.340426 (-1705 2072);
PAINT GREEN (-1705 2072);
DISPLAY INVISIBLE (-1705 2072);
FORCEADD P12V..1
(-1750 3000);
FORCEPROP 3 LASTPIN (-1750 2950) SIG_NAME P12V\g
J 0
(-1740 2960);
DISPLAY 0.659574 (-1740 2960);
PAINT MONO (-1740 2960);
DISPLAY INVISIBLE (-1740 2960);
FORCEPROP 1 LAST HDL_POWER P12V
J 0
(-1950 2850);
DISPLAY 0.872340 (-1950 2850);
PAINT ORANGE (-1950 2850);
DISPLAY INVISIBLE (-1950 2850);
FORCEPROP 1 LAST BODY_TYPE PLUMBING
J 0
(-1795 2957);
DISPLAY 0.340426 (-1795 2957);
PAINT GREEN (-1795 2957);
DISPLAY INVISIBLE (-1795 2957);
FORCEPROP 1 LAST VOLTAGE 12.0V
J 0
(-1795 2957);
DISPLAY 0.340426 (-1795 2957);
PAINT SKYBLUE (-1795 2957);
DISPLAY INVISIBLE (-1795 2957);
FORCEPROP 1 LAST PATH I117
J 0
(-1705 3002);
DISPLAY 0.340426 (-1705 3002);
PAINT GREEN (-1705 3002);
DISPLAY INVISIBLE (-1705 3002);
FORCEPROP 2 LAST CDS_LIB mstr_symbols
J 0
(-1750 3000);
PAINT ORANGE (-1750 3000);
DISPLAY INVISIBLE (-1750 3000);
FORCEPROP 1 LAST SIZE 1B
J 0
(-1705 3022);
DISPLAY 0.340426 (-1705 3022);
PAINT GREEN (-1705 3022);
DISPLAY INVISIBLE (-1705 3022);
FORCEADD GND..1
(-1750 2200);
FORCEPROP 3 LASTPIN (-1750 2250) SIG_NAME GND\g
J 0
(-1740 2260);
DISPLAY 0.659574 (-1740 2260);
PAINT MONO (-1740 2260);
DISPLAY INVISIBLE (-1740 2260);
FORCEPROP 1 LAST BODY_TYPE PLUMBING
J 0
(-1795 2157);
DISPLAY 0.340426 (-1795 2157);
PAINT GREEN (-1795 2157);
DISPLAY INVISIBLE (-1795 2157);
FORCEPROP 1 LAST VOLTAGE 0.0V
J 0
(-1795 2157);
DISPLAY 0.340426 (-1795 2157);
PAINT SKYBLUE (-1795 2157);
DISPLAY INVISIBLE (-1795 2157);
FORCEPROP 1 LAST SIZE 1B
J 0
(-1675 2150);
DISPLAY 0.872340 (-1675 2150);
PAINT AQUA (-1675 2150);
DISPLAY INVISIBLE (-1675 2150);
FORCEPROP 1 LAST PATH I118
J 0
(-1675 2200);
DISPLAY 0.872340 (-1675 2200);
PAINT AQUA (-1675 2200);
DISPLAY INVISIBLE (-1675 2200);
FORCEPROP 2 LAST CDS_LIB mstr_symbols
J 0
(-1750 2200);
PAINT ORANGE (-1750 2200);
DISPLAY INVISIBLE (-1750 2200);
FORCEPROP 1 LAST HDL_POWER GND
J 0
(-1750 2350);
DISPLAY 0.872340 (-1750 2350);
PAINT GREEN (-1750 2350);
DISPLAY INVISIBLE (-1750 2350);
FORCEADD GND..1
(-1750 1250);
FORCEPROP 3 LASTPIN (-1750 1300) SIG_NAME GND\g
J 0
(-1740 1310);
DISPLAY 0.659574 (-1740 1310);
PAINT MONO (-1740 1310);
DISPLAY INVISIBLE (-1740 1310);
FORCEPROP 1 LAST BODY_TYPE PLUMBING
J 0
(-1795 1207);
DISPLAY 0.340426 (-1795 1207);
PAINT GREEN (-1795 1207);
DISPLAY INVISIBLE (-1795 1207);
FORCEPROP 1 LAST VOLTAGE 0.0V
J 0
(-1795 1207);
DISPLAY 0.340426 (-1795 1207);
PAINT SKYBLUE (-1795 1207);
DISPLAY INVISIBLE (-1795 1207);
FORCEPROP 1 LAST SIZE 1B
J 0
(-1675 1200);
DISPLAY 0.872340 (-1675 1200);
PAINT AQUA (-1675 1200);
DISPLAY INVISIBLE (-1675 1200);
FORCEPROP 1 LAST PATH I119
J 0
(-1675 1250);
DISPLAY 0.872340 (-1675 1250);
PAINT AQUA (-1675 1250);
DISPLAY INVISIBLE (-1675 1250);
FORCEPROP 2 LAST CDS_LIB mstr_symbols
J 0
(-1750 1250);
PAINT ORANGE (-1750 1250);
DISPLAY INVISIBLE (-1750 1250);
FORCEPROP 1 LAST HDL_POWER GND
J 0
(-1750 1400);
DISPLAY 0.872340 (-1750 1400);
PAINT GREEN (-1750 1400);
DISPLAY INVISIBLE (-1750 1400);
FORCEADD RES..2
(50 2650);
FORCEPROP 1 LAST PACK_TYPE 0402
J 0
(90 2475);
DISPLAY 0.617021 (90 2475);
PAINT SKYBLUE (90 2475);
FORCEPROP 1 LAST PART_NUMBER G21796-016
J 0
(90 2525);
DISPLAY 0.617021 (90 2525);
PAINT BLUE (90 2525);
FORCEPROP 1 LASTPIN (50 2550) $PN 2
J 0
(55 2560);
DISPLAY 0.617021 (55 2560);
PAINT ORANGE (55 2560);
FORCEPROP 1 LASTPIN (50 2750) $PN 1
J 0
(55 2712);
DISPLAY 0.617021 (55 2712);
PAINT ORANGE (55 2712);
FORCEPROP 1 LAST LOCATION R8D41
J 0
(95 2775);
DISPLAY 0.617021 (95 2775);
PAINT AQUA (95 2775);
FORCEPROP 1 LAST VALUE 10.0K
J 0
(95 2725);
DISPLAY 0.617021 (95 2725);
PAINT SKYBLUE (95 2725);
FORCEPROP 1 LAST TOLERANCE 1%
J 0
(95 2675);
DISPLAY 0.617021 (95 2675);
PAINT SKYBLUE (95 2675);
FORCEPROP 1 LAST MATERIAL CHIP
J 0
(90 2575);
DISPLAY 0.617021 (90 2575);
PAINT SKYBLUE (90 2575);
FORCEPROP 1 LAST WATTAGE 1/16W
J 0
(90 2625);
DISPLAY 0.617021 (90 2625);
PAINT SKYBLUE (90 2625);
FORCEPROP 2 LAST CDS_LIB mstr_discrete
J 0
(50 2650);
PAINT ORANGE (50 2650);
DISPLAY INVISIBLE (50 2650);
FORCEPROP 2 LAST ROOM V_SUPER
J 0
(100 2825);
DISPLAY 1.021277 (100 2825);
PAINT ORANGE (100 2825);
DISPLAY INVISIBLE (100 2825);
FORCEPROP 1 LAST PATH I120
J 0
(100 2825);
DISPLAY 0.978723 (100 2825);
PAINT WHITE (100 2825);
DISPLAY INVISIBLE (100 2825);
FORCEPROP 2 LAST SEC_TYPE 0402
J 0
(100 2875);
DISPLAY 1.021277 (100 2875);
PAINT ORANGE (100 2875);
DISPLAY INVISIBLE (100 2875);
FORCEPROP 2 LAST SEC 1
J 0
(100 2875);
PAINT MONO (100 2875);
DISPLAY INVISIBLE (100 2875);
FORCEADD RES..2
(250 2000);
FORCEPROP 1 LASTPIN (250 1900) $PN 2
J 0
(255 1910);
DISPLAY 0.617021 (255 1910);
PAINT ORANGE (255 1910);
FORCEPROP 1 LAST WATTAGE 1/16W
J 0
(290 1975);
DISPLAY 0.617021 (290 1975);
PAINT SKYBLUE (290 1975);
FORCEPROP 1 LAST MATERIAL CHIP
J 0
(290 1925);
DISPLAY 0.617021 (290 1925);
PAINT SKYBLUE (290 1925);
FORCEPROP 1 LAST PACK_TYPE 0402
J 0
(290 1825);
DISPLAY 0.617021 (290 1825);
PAINT SKYBLUE (290 1825);
FORCEPROP 1 LAST PART_NUMBER G21796-016
J 0
(290 1875);
DISPLAY 0.617021 (290 1875);
PAINT BLUE (290 1875);
FORCEPROP 1 LAST TOLERANCE 1%
J 0
(295 2025);
DISPLAY 0.617021 (295 2025);
PAINT SKYBLUE (295 2025);
FORCEPROP 1 LASTPIN (250 2100) $PN 1
J 0
(255 2062);
DISPLAY 0.617021 (255 2062);
PAINT ORANGE (255 2062);
FORCEPROP 1 LAST VALUE 10.0K
J 0
(295 2075);
DISPLAY 0.617021 (295 2075);
PAINT SKYBLUE (295 2075);
FORCEPROP 1 LAST LOCATION R2P18
J 0
(295 2125);
DISPLAY 0.617021 (295 2125);
PAINT AQUA (295 2125);
FORCEPROP 2 LAST CDS_LIB mstr_discrete
J 0
(250 2000);
PAINT ORANGE (250 2000);
DISPLAY INVISIBLE (250 2000);
FORCEPROP 2 LAST ROOM V_SUPER
J 0
(300 2175);
DISPLAY 1.021277 (300 2175);
PAINT ORANGE (300 2175);
DISPLAY INVISIBLE (300 2175);
FORCEPROP 1 LAST PATH I121
J 0
(300 2175);
DISPLAY 0.978723 (300 2175);
PAINT WHITE (300 2175);
DISPLAY INVISIBLE (300 2175);
FORCEPROP 2 LAST SEC_TYPE 0402
J 0
(300 2225);
DISPLAY 1.021277 (300 2225);
PAINT ORANGE (300 2225);
DISPLAY INVISIBLE (300 2225);
FORCEPROP 2 LAST SEC 1
J 0
(300 2225);
PAINT MONO (300 2225);
DISPLAY INVISIBLE (300 2225);
FORCEADD RES..2
(750 2200);
FORCEPROP 1 LAST PACK_TYPE 0402
J 0
(790 2025);
DISPLAY 0.617021 (790 2025);
PAINT SKYBLUE (790 2025);
FORCEPROP 1 LASTPIN (750 2300) $PN 1
J 0
(755 2262);
DISPLAY 0.617021 (755 2262);
PAINT ORANGE (755 2262);
FORCEPROP 1 LASTPIN (750 2100) $PN 2
J 0
(755 2110);
DISPLAY 0.617021 (755 2110);
PAINT ORANGE (755 2110);
FORCEPROP 1 LAST WATTAGE 1/16W
J 0
(790 2175);
DISPLAY 0.617021 (790 2175);
PAINT SKYBLUE (790 2175);
FORCEPROP 1 LAST MATERIAL CHIP
J 0
(790 2125);
DISPLAY 0.617021 (790 2125);
PAINT SKYBLUE (790 2125);
FORCEPROP 1 LAST TOLERANCE 1%
J 0
(795 2225);
DISPLAY 0.617021 (795 2225);
PAINT SKYBLUE (795 2225);
FORCEPROP 1 LAST LOCATION R2P21
J 0
(795 2325);
DISPLAY 0.617021 (795 2325);
PAINT AQUA (795 2325);
FORCEPROP 1 LAST VALUE 10.0K
J 0
(795 2275);
DISPLAY 0.617021 (795 2275);
PAINT SKYBLUE (795 2275);
FORCEPROP 1 LAST PART_NUMBER G21796-016
J 0
(790 2075);
DISPLAY 0.617021 (790 2075);
PAINT BLUE (790 2075);
FORCEPROP 2 LAST CDS_LIB mstr_discrete
J 0
(750 2200);
PAINT ORANGE (750 2200);
DISPLAY INVISIBLE (750 2200);
FORCEPROP 2 LAST ROOM V_SUPER
J 0
(800 2375);
DISPLAY 1.021277 (800 2375);
PAINT ORANGE (800 2375);
DISPLAY INVISIBLE (800 2375);
FORCEPROP 1 LAST PATH I122
J 0
(800 2375);
DISPLAY 0.978723 (800 2375);
PAINT WHITE (800 2375);
DISPLAY INVISIBLE (800 2375);
FORCEPROP 2 LAST SEC 1
J 0
(800 2425);
PAINT MONO (800 2425);
DISPLAY INVISIBLE (800 2425);
FORCEPROP 2 LAST SEC_TYPE 0402
J 0
(800 2425);
DISPLAY 1.021277 (800 2425);
PAINT ORANGE (800 2425);
DISPLAY INVISIBLE (800 2425);
FORCEADD P3V3_STBY..1
(50 2850);
FORCEPROP 3 LASTPIN (50 2800) SIG_NAME P3V3_STBY\g
J 0
(60 2810);
DISPLAY 0.659574 (60 2810);
PAINT MONO (60 2810);
DISPLAY INVISIBLE (60 2810);
FORCEPROP 1 LAST HDL_POWER P3V3_STBY
J 0
(-250 2725);
DISPLAY 0.872340 (-250 2725);
PAINT ORANGE (-250 2725);
DISPLAY INVISIBLE (-250 2725);
FORCEPROP 1 LAST BODY_TYPE PLUMBING
J 0
(5 2807);
DISPLAY 0.340426 (5 2807);
PAINT GREEN (5 2807);
DISPLAY INVISIBLE (5 2807);
FORCEPROP 1 LAST VOLTAGE 3.3V
J 0
(5 2807);
DISPLAY 0.340426 (5 2807);
PAINT SKYBLUE (5 2807);
DISPLAY INVISIBLE (5 2807);
FORCEPROP 1 LAST PATH I123
J 0
(95 2852);
DISPLAY 0.340426 (95 2852);
PAINT GREEN (95 2852);
DISPLAY INVISIBLE (95 2852);
FORCEPROP 1 LAST SIZE 1B
J 0
(95 2872);
DISPLAY 0.340426 (95 2872);
PAINT GREEN (95 2872);
DISPLAY INVISIBLE (95 2872);
FORCEPROP 2 LAST CDS_LIB mstr_symbols
J 0
(50 2850);
PAINT ORANGE (50 2850);
DISPLAY INVISIBLE (50 2850);
FORCEADD FET_N..8
(750 1750);
FORCEPROP 1 LAST MATERIAL FET
J 0
(950 1650);
DISPLAY 0.617021 (950 1650);
PAINT SKYBLUE (950 1650);
FORCEPROP 1 LAST VALUE 2N7002
J 0
(950 1700);
DISPLAY 0.617021 (950 1700);
PAINT SKYBLUE (950 1700);
FORCEPROP 1 LAST PART_NUMBER C79254-001
J 0
(950 1550);
DISPLAY 0.617021 (950 1550);
PAINT BLUE (950 1550);
FORCEPROP 1 LAST LOCATION Q2P2
J 0
(950 1750);
DISPLAY 0.617021 (950 1750);
PAINT AQUA (950 1750);
FORCEPROP 1 LASTPIN (550 1650) $PN 1
J 2
(553 1665);
DISPLAY 0.872340 (553 1665);
PAINT WHITE (553 1665);
DISPLAY INVISIBLE (553 1665);
FORCEPROP 2 LAST CDS_LIB mstr_discrete
J 0
(750 1750);
PAINT ORANGE (750 1750);
DISPLAY INVISIBLE (750 1750);
FORCEPROP 1 LAST PACK_TYPE SOT23
J 0
(950 1600);
DISPLAY 0.978723 (950 1600);
PAINT SKYBLUE (950 1600);
DISPLAY INVISIBLE (950 1600);
FORCEPROP 1 LASTPIN (750 1550) $PN 2
J 2
(808 1550);
DISPLAY 0.872340 (808 1550);
PAINT WHITE (808 1550);
DISPLAY INVISIBLE (808 1550);
FORCEPROP 2 LAST $SEC 1
J 0
(950 1850);
PAINT MONO (950 1850);
DISPLAY INVISIBLE (950 1850);
FORCEPROP 1 LAST PATH I124
J 0
(950 1800);
DISPLAY 0.978723 (950 1800);
PAINT BLUE (950 1800);
DISPLAY INVISIBLE (950 1800);
FORCEPROP 2 LAST ROOM V_SUPER
J 0
(950 1800);
DISPLAY 1.021277 (950 1800);
PAINT ORANGE (950 1800);
DISPLAY INVISIBLE (950 1800);
FORCEPROP 2 LAST CDS_SEC 1
J 0
(950 1850);
PAINT MONO (950 1850);
DISPLAY INVISIBLE (950 1850);
FORCEPROP 1 LASTPIN (750 1950) $PN 3
J 2
(803 1915);
DISPLAY 0.872340 (803 1915);
PAINT WHITE (803 1915);
DISPLAY INVISIBLE (803 1915);
FORCEADD GND..1
(750 1450);
FORCEPROP 3 LASTPIN (750 1500) SIG_NAME GND\g
J 0
(760 1510);
DISPLAY 0.659574 (760 1510);
PAINT MONO (760 1510);
DISPLAY INVISIBLE (760 1510);
FORCEPROP 1 LAST PATH I125
J 0
(825 1450);
DISPLAY 0.872340 (825 1450);
PAINT AQUA (825 1450);
DISPLAY INVISIBLE (825 1450);
FORCEPROP 1 LAST BODY_TYPE PLUMBING
J 0
(705 1407);
DISPLAY 0.340426 (705 1407);
PAINT GREEN (705 1407);
DISPLAY INVISIBLE (705 1407);
FORCEPROP 1 LAST SIZE 1B
J 0
(825 1400);
DISPLAY 0.872340 (825 1400);
PAINT AQUA (825 1400);
DISPLAY INVISIBLE (825 1400);
FORCEPROP 2 LAST CDS_LIB mstr_symbols
J 0
(750 1450);
PAINT ORANGE (750 1450);
DISPLAY INVISIBLE (750 1450);
FORCEPROP 1 LAST VOLTAGE 0.0V
J 0
(705 1407);
DISPLAY 0.340426 (705 1407);
PAINT SKYBLUE (705 1407);
DISPLAY INVISIBLE (705 1407);
FORCEPROP 1 LAST HDL_POWER GND
J 0
(750 1600);
DISPLAY 0.872340 (750 1600);
PAINT GREEN (750 1600);
DISPLAY INVISIBLE (750 1600);
FORCEADD P3V3_STBY..1
(250 2300);
FORCEPROP 3 LASTPIN (250 2250) SIG_NAME P3V3_STBY\g
J 0
(260 2260);
DISPLAY 0.659574 (260 2260);
PAINT MONO (260 2260);
DISPLAY INVISIBLE (260 2260);
FORCEPROP 1 LAST HDL_POWER P3V3_STBY
J 0
(-50 2175);
DISPLAY 0.872340 (-50 2175);
PAINT ORANGE (-50 2175);
DISPLAY INVISIBLE (-50 2175);
FORCEPROP 1 LAST BODY_TYPE PLUMBING
J 0
(205 2257);
DISPLAY 0.340426 (205 2257);
PAINT GREEN (205 2257);
DISPLAY INVISIBLE (205 2257);
FORCEPROP 1 LAST VOLTAGE 3.3V
J 0
(205 2257);
DISPLAY 0.340426 (205 2257);
PAINT SKYBLUE (205 2257);
DISPLAY INVISIBLE (205 2257);
FORCEPROP 2 LAST CDS_LIB mstr_symbols
J 0
(250 2300);
PAINT ORANGE (250 2300);
DISPLAY INVISIBLE (250 2300);
FORCEPROP 1 LAST SIZE 1B
J 0
(295 2322);
DISPLAY 0.340426 (295 2322);
PAINT GREEN (295 2322);
DISPLAY INVISIBLE (295 2322);
FORCEPROP 1 LAST PATH I126
J 0
(295 2302);
DISPLAY 0.340426 (295 2302);
PAINT GREEN (295 2302);
DISPLAY INVISIBLE (295 2302);
FORCEADD P3V3_STBY..1
(750 2600);
FORCEPROP 3 LASTPIN (750 2550) SIG_NAME P3V3_STBY\g
J 0
(760 2560);
DISPLAY 0.659574 (760 2560);
PAINT MONO (760 2560);
DISPLAY INVISIBLE (760 2560);
FORCEPROP 1 LAST HDL_POWER P3V3_STBY
J 0
(450 2475);
DISPLAY 0.872340 (450 2475);
PAINT ORANGE (450 2475);
DISPLAY INVISIBLE (450 2475);
FORCEPROP 1 LAST BODY_TYPE PLUMBING
J 0
(705 2557);
DISPLAY 0.340426 (705 2557);
PAINT GREEN (705 2557);
DISPLAY INVISIBLE (705 2557);
FORCEPROP 1 LAST VOLTAGE 3.3V
J 0
(705 2557);
DISPLAY 0.340426 (705 2557);
PAINT SKYBLUE (705 2557);
DISPLAY INVISIBLE (705 2557);
FORCEPROP 1 LAST PATH I127
J 0
(795 2602);
DISPLAY 0.340426 (795 2602);
PAINT GREEN (795 2602);
DISPLAY INVISIBLE (795 2602);
FORCEPROP 2 LAST CDS_LIB mstr_symbols
J 0
(750 2600);
PAINT ORANGE (750 2600);
DISPLAY INVISIBLE (750 2600);
FORCEPROP 1 LAST SIZE 1B
J 0
(795 2622);
DISPLAY 0.340426 (795 2622);
PAINT GREEN (795 2622);
DISPLAY INVISIBLE (795 2622);
FORCEADD DIODE..3
(1050 3400);
FORCEPROP 1 LASTPIN (950 3400) $PN 1
J 2
(985 3410);
DISPLAY 0.617021 (985 3410);
PAINT AQUA (985 3410);
FORCEPROP 1 LAST LOCATION CR8E1
J 0
(1023 3556);
DISPLAY 0.617021 (1023 3556);
PAINT AQUA (1023 3556);
FORCEPROP 1 LAST VALUE BAT54WS
J 0
(1025 3275);
DISPLAY 0.617021 (1025 3275);
PAINT SKYBLUE (1025 3275);
FORCEPROP 1 LAST PACK_TYPE SMLF
J 0
(1025 3160);
DISPLAY 0.617021 (1025 3160);
PAINT SKYBLUE (1025 3160);
FORCEPROP 1 LAST MATERIAL IC
J 0
(1025 3222);
DISPLAY 0.617021 (1025 3222);
PAINT SKYBLUE (1025 3222);
FORCEPROP 1 LASTPIN (1150 3400) $PN 2
J 0
(1125 3410);
DISPLAY 0.617021 (1125 3410);
PAINT AQUA (1125 3410);
FORCEPROP 1 LAST PART_NUMBER C73510-001
J 0
(1025 3500);
DISPLAY 0.617021 (1025 3500);
PAINT BLUE (1025 3500);
FORCEPROP 2 LAST CDS_LIB mstr_discrete
J 0
(1050 3400);
PAINT ORANGE (1050 3400);
DISPLAY INVISIBLE (1050 3400);
FORCEPROP 1 LAST PATH I128
J 0
(1030 3610);
DISPLAY 0.978723 (1030 3610);
PAINT PINK (1030 3610);
DISPLAY INVISIBLE (1030 3610);
FORCEPROP 2 LAST SEC_TYPE SMLF
J 0
(1050 3675);
DISPLAY 1.021277 (1050 3675);
PAINT ORANGE (1050 3675);
DISPLAY INVISIBLE (1050 3675);
FORCEPROP 2 LAST SEC 1
J 0
(1050 3675);
PAINT MONO (1050 3675);
DISPLAY INVISIBLE (1050 3675);
FORCEADD GND..1
(-2200 4250);
FORCEPROP 3 LASTPIN (-2200 4300) SIG_NAME GND\g
J 0
(-2190 4310);
DISPLAY 0.659574 (-2190 4310);
PAINT MONO (-2190 4310);
DISPLAY INVISIBLE (-2190 4310);
FORCEPROP 2 LAST ROOM BATTERY_CIRCUIT
J 0
(-2525 4325);
DISPLAY 0.702128 (-2525 4325);
PAINT ORANGE (-2525 4325);
DISPLAY INVISIBLE (-2525 4325);
FORCEPROP 1 LAST PATH I43
J 0
(-2125 4250);
DISPLAY 1.170213 (-2125 4250);
PAINT GREEN (-2125 4250);
DISPLAY INVISIBLE (-2125 4250);
FORCEPROP 1 LAST BODY_TYPE PLUMBING
J 0
(-2245 4207);
DISPLAY 0.340426 (-2245 4207);
PAINT GREEN (-2245 4207);
DISPLAY INVISIBLE (-2245 4207);
FORCEPROP 2 LAST CDS_LIB mstr_symbols
J 0
(-2200 4250);
DISPLAY 1.319149 (-2200 4250);
PAINT ORANGE (-2200 4250);
DISPLAY INVISIBLE (-2200 4250);
FORCEPROP 1 LAST SIZE 1B
J 0
(-2125 4200);
DISPLAY 0.702128 (-2125 4200);
PAINT GREEN (-2125 4200);
DISPLAY INVISIBLE (-2125 4200);
FORCEPROP 1 LAST VOLTAGE 0
J 0
(-2200 4250);
PAINT SKYBLUE (-2200 4250);
DISPLAY INVISIBLE (-2200 4250);
FORCEPROP 1 LAST HDL_POWER GND
J 0
(-2200 4400);
DISPLAY 0.702128 (-2200 4400);
PAINT GREEN (-2200 4400);
DISPLAY INVISIBLE (-2200 4400);
FORCEADD OFFPAGE..2
(-2800 4300);
FORCEPROP 2 LAST $XR0 169 
J 0
(-2611 4300);
DISPLAY 0.638298 (-2611 4300);
PAINT MONO (-2611 4300);
FORCEPROP 1 LAST COMMENT_BODY TRUE
J 0
(-2845 4205);
DISPLAY 0.702128 (-2845 4205);
PAINT GREEN (-2845 4205);
DISPLAY INVISIBLE (-2845 4205);
FORCEPROP 2 LAST CDS_LIB mstr_standard
J 0
(-2800 4300);
DISPLAY 1.148936 (-2800 4300);
PAINT ORANGE (-2800 4300);
DISPLAY INVISIBLE (-2800 4300);
FORCEPROP 2 LAST ROOM BATTERY_CIRCUIT
J 0
(-2600 4350);
DISPLAY 0.702128 (-2600 4350);
PAINT ORANGE (-2600 4350);
DISPLAY INVISIBLE (-2600 4350);
FORCEPROP 2 LAST PATH I45
J 0
(-2600 4350);
PAINT MONO (-2600 4350);
DISPLAY INVISIBLE (-2600 4350);
FORCEPROP 1 LAST OFFPAGE TRUE
J 0
(-2475 4175);
PAINT GREEN (-2475 4175);
DISPLAY INVISIBLE (-2475 4175);
FORCEADD RES..1
(-3650 4550);
FORCEPROP 1 LASTPIN (-3750 4550) $PN 1
J 0
(-3738 4562);
DISPLAY 0.617021 (-3738 4562);
PAINT MONO (-3738 4562);
FORCEPROP 1 LAST WATTAGE 1/16W
J 2
(-3675 4400);
DISPLAY 0.617021 (-3675 4400);
PAINT SKYBLUE (-3675 4400);
FORCEPROP 1 LAST TOLERANCE 1%
J 0
(-3650 4450);
DISPLAY 0.617021 (-3650 4450);
PAINT SKYBLUE (-3650 4450);
FORCEPROP 1 LAST VALUE 1.00K
J 2
(-3675 4450);
DISPLAY 0.617021 (-3675 4450);
PAINT SKYBLUE (-3675 4450);
FORCEPROP 1 LASTPIN (-3550 4550) $PN 2
J 0
(-3588 4562);
DISPLAY 0.617021 (-3588 4562);
PAINT MONO (-3588 4562);
FORCEPROP 1 LAST MATERIAL CHIP
J 0
(-3650 4400);
DISPLAY 0.617021 (-3650 4400);
PAINT SKYBLUE (-3650 4400);
FORCEPROP 1 LAST PART_NUMBER G21796-026
J 0
(-3825 4650);
DISPLAY 0.617021 (-3825 4650);
PAINT BLUE (-3825 4650);
FORCEPROP 1 LAST LOCATION R2U43
J 0
(-3700 4600);
DISPLAY 0.617021 (-3700 4600);
PAINT AQUA (-3700 4600);
FORCEPROP 1 LAST PACK_TYPE 0402
J 0
(-3500 4400);
DISPLAY 0.617021 (-3500 4400);
PAINT SKYBLUE (-3500 4400);
FORCEPROP 2 LAST CDS_LIB mstr_discrete
J 0
(-3650 4550);
DISPLAY 1.319149 (-3650 4550);
PAINT ORANGE (-3650 4550);
DISPLAY INVISIBLE (-3650 4550);
FORCEPROP 2 LAST CDS_LOCATION R2U43
J 0
(-3700 4600);
DISPLAY 0.617021 (-3700 4600);
PAINT AQUA (-3700 4600);
DISPLAY INVISIBLE (-3700 4600);
FORCEPROP 2 LAST BOM_COST SB
J 0
(-3825 4700);
PAINT MONO (-3825 4700);
DISPLAY INVISIBLE (-3825 4700);
FORCEPROP 2 LAST SEC_TYPE 0402
J 0
(-3700 4775);
DISPLAY 1.021277 (-3700 4775);
PAINT ORANGE (-3700 4775);
DISPLAY INVISIBLE (-3700 4775);
FORCEPROP 2 LAST SEC 1
J 0
(-3700 4775);
DISPLAY 0.680851 (-3700 4775);
PAINT MONO (-3700 4775);
DISPLAY INVISIBLE (-3700 4775);
FORCEPROP 1 LAST PATH I46
J 0
(-3700 4700);
DISPLAY 1.319149 (-3700 4700);
PAINT GREEN (-3700 4700);
DISPLAY INVISIBLE (-3700 4700);
FORCEPROP 2 LAST ROOM SB_VRD
J 0
(-3700 4700);
DISPLAY 0.702128 (-3700 4700);
PAINT ORANGE (-3700 4700);
DISPLAY INVISIBLE (-3700 4700);
FORCEADD BATTERY..1
(-4375 4200);
FORCEPROP 1 LAST PART_NUMBER 202168-001
J 1
(-4375 4125);
DISPLAY 0.617021 (-4375 4125);
PAINT BLUE (-4375 4125);
FORCEPROP 1 LAST LOCATION BT8G1
J 0
(-4420 4263);
DISPLAY 0.617021 (-4420 4263);
PAINT AQUA (-4420 4263);
FORCEPROP 2 LAST BOM_COST SB
J 0
(-4400 4300);
PAINT MONO (-4400 4300);
DISPLAY INVISIBLE (-4400 4300);
FORCEPROP 2 LAST CDS_LIB mstr_misc
J 0
(-4375 4200);
DISPLAY 1.319149 (-4375 4200);
PAINT ORANGE (-4375 4200);
DISPLAY INVISIBLE (-4375 4200);
FORCEPROP 2 LAST CDS_LOCATION BT8G1
J 0
(-4420 4263);
DISPLAY 0.617021 (-4420 4263);
PAINT AQUA (-4420 4263);
DISPLAY INVISIBLE (-4420 4263);
FORCEPROP 1 LAST PACK_TYPE PLCLF
J 0
(-4420 4325);
PAINT SKYBLUE (-4420 4325);
DISPLAY INVISIBLE (-4420 4325);
FORCEPROP 2 LAST ROOM SB_VRD
J 0
(-4400 4325);
DISPLAY 0.702128 (-4400 4325);
PAINT ORANGE (-4400 4325);
DISPLAY INVISIBLE (-4400 4325);
FORCEPROP 1 LAST PATH I47
J 0
(-4425 4370);
DISPLAY 1.170213 (-4425 4370);
PAINT GREEN (-4425 4370);
DISPLAY INVISIBLE (-4425 4370);
FORCEADD VERT_BATT_3PIN..1
(-4800 4550);
FORCEPROP 2 LASTPIN (-4950 4550) $PN 3
J 2
(-4960 4560);
DISPLAY 0.617021 (-4960 4560);
PAINT ORANGE (-4960 4560);
FORCEPROP 1 LAST PART_NUMBER C68619-005
J 0
(-4950 4400);
DISPLAY 0.617021 (-4950 4400);
PAINT BLUE (-4950 4400);
FORCEPROP 2 LASTPIN (-4650 4500) $PN 2
J 0
(-4640 4510);
DISPLAY 0.617021 (-4640 4510);
PAINT ORANGE (-4640 4510);
FORCEPROP 2 LASTPIN (-4650 4600) $PN 1
J 0
(-4640 4610);
DISPLAY 0.617021 (-4640 4610);
PAINT ORANGE (-4640 4610);
FORCEPROP 1 LAST MATERIAL 3PVERT
J 0
(-4950 4650);
DISPLAY 0.617021 (-4950 4650);
PAINT SKYBLUE (-4950 4650);
FORCEPROP 1 LAST LOCATION XBT8G1
J 0
(-4950 4700);
DISPLAY 0.617021 (-4950 4700);
PAINT AQUA (-4950 4700);
FORCEPROP 2 LAST CDS_LIB mstr_discrete
J 0
(-4800 4550);
PAINT ORANGE (-4800 4550);
DISPLAY INVISIBLE (-4800 4550);
FORCEPROP 1 LAST PATH I51
J 0
(-4650 4450);
DISPLAY 0.872340 (-4650 4450);
PAINT WHITE (-4650 4450);
DISPLAY INVISIBLE (-4650 4450);
FORCEPROP 0 LAST ROOM SB_VRD
J 0
(-4950 4900);
DISPLAY 1.382979 (-4950 4900);
PAINT ORANGE (-4950 4900);
DISPLAY INVISIBLE (-4950 4900);
FORCEPROP 2 LAST SEC_TYPE PIP
J 0
(-4950 4750);
DISPLAY 1.021277 (-4950 4750);
PAINT ORANGE (-4950 4750);
DISPLAY INVISIBLE (-4950 4750);
FORCEPROP 2 LAST SEC 1
J 0
(-4950 4750);
DISPLAY 0.680851 (-4950 4750);
PAINT MONO (-4950 4750);
DISPLAY INVISIBLE (-4950 4750);
FORCEPROP 2 LAST CDS_LOCATION XBT8G1
J 0
(-4950 4700);
DISPLAY 0.617021 (-4950 4700);
PAINT AQUA (-4950 4700);
DISPLAY INVISIBLE (-4950 4700);
FORCEPROP 1 LAST PACK_TYPE PIP
J 0
(-4950 4750);
DISPLAY 0.872340 (-4950 4750);
PAINT SKYBLUE (-4950 4750);
DISPLAY INVISIBLE (-4950 4750);
FORCEADD GND..1
(-5050 4250);
FORCEPROP 3 LASTPIN (-5050 4300) SIG_NAME GND\g
J 0
(-5040 4310);
DISPLAY 0.659574 (-5040 4310);
PAINT MONO (-5040 4310);
DISPLAY INVISIBLE (-5040 4310);
FORCEPROP 2 LAST ROOM SB
J 0
(-5200 4325);
DISPLAY 0.702128 (-5200 4325);
PAINT ORANGE (-5200 4325);
DISPLAY INVISIBLE (-5200 4325);
FORCEPROP 1 LAST BODY_TYPE PLUMBING
J 0
(-5095 4207);
DISPLAY 0.340426 (-5095 4207);
PAINT GREEN (-5095 4207);
DISPLAY INVISIBLE (-5095 4207);
FORCEPROP 1 LAST SIZE 1B
J 0
(-4975 4200);
DISPLAY 0.702128 (-4975 4200);
PAINT GREEN (-4975 4200);
DISPLAY INVISIBLE (-4975 4200);
FORCEPROP 1 LAST VOLTAGE 0
J 0
(-5050 4250);
PAINT SKYBLUE (-5050 4250);
DISPLAY INVISIBLE (-5050 4250);
FORCEPROP 2 LAST CDS_LIB mstr_symbols
J 0
(-5050 4250);
DISPLAY 1.319149 (-5050 4250);
PAINT ORANGE (-5050 4250);
DISPLAY INVISIBLE (-5050 4250);
FORCEPROP 1 LAST PATH I52
J 0
(-4975 4250);
DISPLAY 1.212766 (-4975 4250);
PAINT AQUA (-4975 4250);
DISPLAY INVISIBLE (-4975 4250);
FORCEPROP 1 LAST HDL_POWER GND
J 0
(-5050 4400);
DISPLAY 0.702128 (-5050 4400);
PAINT GREEN (-5050 4400);
DISPLAY INVISIBLE (-5050 4400);
FORCEADD DIODE2A_DUAL..1
(-2700 4650);
FORCEPROP 2 LASTPIN (-2850 4550) $PN 2
J 2
(-2860 4560);
DISPLAY 0.617021 (-2860 4560);
PAINT MONO (-2860 4560);
FORCEPROP 2 LASTPIN (-2850 4750) $PN 1
J 2
(-2860 4760);
DISPLAY 0.617021 (-2860 4760);
PAINT MONO (-2860 4760);
FORCEPROP 1 LAST LOCATION CR2U1
J 0
(-2850 4850);
DISPLAY 0.617021 (-2850 4850);
PAINT AQUA (-2850 4850);
FORCEPROP 1 LAST MATERIAL DIO
J 2
(-2725 4625);
DISPLAY 0.617021 (-2725 4625);
PAINT SKYBLUE (-2725 4625);
FORCEPROP 1 LAST PACK_TYPE SMLF
J 0
(-2600 4525);
DISPLAY 0.617021 (-2600 4525);
PAINT SKYBLUE (-2600 4525);
FORCEPROP 1 LAST VALUE BAS70-05
J 2
(-2400 4575);
DISPLAY 0.617021 (-2400 4575);
PAINT SKYBLUE (-2400 4575);
FORCEPROP 1 LAST PART_NUMBER C90169-001
J 0
(-2850 4900);
DISPLAY 0.617021 (-2850 4900);
PAINT BLUE (-2850 4900);
FORCEPROP 2 LASTPIN (-2550 4650) $PN 3
J 0
(-2540 4660);
DISPLAY 0.617021 (-2540 4660);
PAINT MONO (-2540 4660);
FORCEPROP 2 LAST SEC_TYPE SMLF
J 0
(-2850 5000);
DISPLAY 1.127660 (-2850 5000);
PAINT MONO (-2850 5000);
DISPLAY INVISIBLE (-2850 5000);
FORCEPROP 2 LAST SEC 1
J 0
(-2850 5000);
DISPLAY 0.936170 (-2850 5000);
PAINT MONO (-2850 5000);
DISPLAY INVISIBLE (-2850 5000);
FORCEPROP 2 LAST CDS_LOCATION CR2U1
J 0
(-2850 4850);
DISPLAY 0.617021 (-2850 4850);
PAINT AQUA (-2850 4850);
DISPLAY INVISIBLE (-2850 4850);
FORCEPROP 1 LAST PATH I53
J 0
(-2850 4950);
DISPLAY 1.361702 (-2850 4950);
PAINT BLUE (-2850 4950);
DISPLAY INVISIBLE (-2850 4950);
FORCEPROP 2 LAST ROOM SB_VRD
J 0
(-2850 4950);
DISPLAY 1.404255 (-2850 4950);
PAINT ORANGE (-2850 4950);
DISPLAY INVISIBLE (-2850 4950);
FORCEPROP 2 LAST CDS_LIB mstr_discrete
J 0
(-2700 4650);
DISPLAY 1.319149 (-2700 4650);
PAINT ORANGE (-2700 4650);
DISPLAY INVISIBLE (-2700 4650);
FORCEADD P3V3_STBY..1
(-3250 4975);
FORCEPROP 3 LASTPIN (-3250 4925) SIG_NAME P3V3_STBY\g
J 0
(-3240 4935);
DISPLAY 0.659574 (-3240 4935);
PAINT MONO (-3240 4935);
DISPLAY INVISIBLE (-3240 4935);
FORCEPROP 1 LAST VOLTAGE 3.3V
J 0
(-3295 4932);
DISPLAY 0.340426 (-3295 4932);
PAINT SKYBLUE (-3295 4932);
DISPLAY INVISIBLE (-3295 4932);
FORCEPROP 1 LAST SIZE 1B
J 0
(-3205 4997);
DISPLAY 0.340426 (-3205 4997);
PAINT GREEN (-3205 4997);
DISPLAY INVISIBLE (-3205 4997);
FORCEPROP 2 LAST CDS_LIB mstr_symbols
J 0
(-3250 4975);
PAINT ORANGE (-3250 4975);
DISPLAY INVISIBLE (-3250 4975);
FORCEPROP 1 LAST BODY_TYPE PLUMBING
J 0
(-3295 4932);
DISPLAY 0.340426 (-3295 4932);
PAINT GREEN (-3295 4932);
DISPLAY INVISIBLE (-3295 4932);
FORCEPROP 1 LAST PATH I54
J 0
(-3205 4977);
DISPLAY 0.340426 (-3205 4977);
PAINT GREEN (-3205 4977);
DISPLAY INVISIBLE (-3205 4977);
FORCEPROP 1 LAST HDL_POWER P3V3_STBY
J 0
(-3550 4850);
DISPLAY 0.872340 (-3550 4850);
PAINT ORANGE (-3550 4850);
DISPLAY INVISIBLE (-3550 4850);
FORCEADD P3V3_STBY..1
(-25 5000);
FORCEPROP 3 LASTPIN (-25 4950) SIG_NAME P3V3_STBY\g
J 0
(-15 4960);
DISPLAY 0.659574 (-15 4960);
PAINT MONO (-15 4960);
DISPLAY INVISIBLE (-15 4960);
FORCEPROP 1 LAST HDL_POWER P3V3_STBY
J 0
(-325 4875);
DISPLAY 0.872340 (-325 4875);
PAINT ORANGE (-325 4875);
DISPLAY INVISIBLE (-325 4875);
FORCEPROP 1 LAST BODY_TYPE PLUMBING
J 0
(-70 4957);
DISPLAY 0.340426 (-70 4957);
PAINT GREEN (-70 4957);
DISPLAY INVISIBLE (-70 4957);
FORCEPROP 2 LAST CDS_LIB mstr_symbols
J 0
(-25 5000);
PAINT ORANGE (-25 5000);
DISPLAY INVISIBLE (-25 5000);
FORCEPROP 1 LAST VOLTAGE 3.3V
J 0
(-70 4957);
DISPLAY 0.340426 (-70 4957);
PAINT SKYBLUE (-70 4957);
DISPLAY INVISIBLE (-70 4957);
FORCEPROP 1 LAST PATH I56
J 0
(20 5002);
DISPLAY 0.340426 (20 5002);
PAINT GREEN (20 5002);
DISPLAY INVISIBLE (20 5002);
FORCEPROP 1 LAST SIZE 1B
J 0
(20 5022);
DISPLAY 0.340426 (20 5022);
PAINT GREEN (20 5022);
DISPLAY INVISIBLE (20 5022);
FORCEADD P12V_STBY..1
(-525 5000);
FORCEPROP 3 LASTPIN (-525 4950) SIG_NAME P12V_STBY\g
J 0
(-515 4960);
DISPLAY 0.659574 (-515 4960);
PAINT MONO (-515 4960);
DISPLAY INVISIBLE (-515 4960);
FORCEPROP 1 LAST HDL_POWER P12V_STBY
J 0
(-825 4875);
DISPLAY 0.872340 (-825 4875);
PAINT ORANGE (-825 4875);
DISPLAY INVISIBLE (-825 4875);
FORCEPROP 1 LAST BODY_TYPE PLUMBING
J 0
(-570 4957);
DISPLAY 0.340426 (-570 4957);
PAINT GREEN (-570 4957);
DISPLAY INVISIBLE (-570 4957);
FORCEPROP 2 LAST CDS_LIB mstr_symbols
J 0
(-525 5000);
PAINT ORANGE (-525 5000);
DISPLAY INVISIBLE (-525 5000);
FORCEPROP 1 LAST VOLTAGE 12.0V
J 0
(-570 4957);
DISPLAY 0.340426 (-570 4957);
PAINT SKYBLUE (-570 4957);
DISPLAY INVISIBLE (-570 4957);
FORCEPROP 1 LAST PATH I57
J 0
(-480 5002);
DISPLAY 0.340426 (-480 5002);
PAINT GREEN (-480 5002);
DISPLAY INVISIBLE (-480 5002);
FORCEPROP 1 LAST SIZE 1B
J 0
(-480 5022);
DISPLAY 0.340426 (-480 5022);
PAINT GREEN (-480 5022);
DISPLAY INVISIBLE (-480 5022);
FORCEADD P3V3_STBY..1
(1325 4900);
FORCEPROP 3 LASTPIN (1325 4850) SIG_NAME P3V3_STBY\g
J 0
(1335 4860);
DISPLAY 0.659574 (1335 4860);
PAINT MONO (1335 4860);
DISPLAY INVISIBLE (1335 4860);
FORCEPROP 1 LAST HDL_POWER P3V3_STBY
J 0
(1025 4775);
DISPLAY 0.872340 (1025 4775);
PAINT ORANGE (1025 4775);
DISPLAY INVISIBLE (1025 4775);
FORCEPROP 1 LAST BODY_TYPE PLUMBING
J 0
(1280 4857);
DISPLAY 0.340426 (1280 4857);
PAINT GREEN (1280 4857);
DISPLAY INVISIBLE (1280 4857);
FORCEPROP 1 LAST VOLTAGE 3.3V
J 0
(1280 4857);
DISPLAY 0.340426 (1280 4857);
PAINT SKYBLUE (1280 4857);
DISPLAY INVISIBLE (1280 4857);
FORCEPROP 1 LAST PATH I58
J 0
(1370 4902);
DISPLAY 0.340426 (1370 4902);
PAINT GREEN (1370 4902);
DISPLAY INVISIBLE (1370 4902);
FORCEPROP 1 LAST SIZE 1B
J 0
(1370 4922);
DISPLAY 0.340426 (1370 4922);
PAINT GREEN (1370 4922);
DISPLAY INVISIBLE (1370 4922);
FORCEPROP 2 LAST CDS_LIB mstr_symbols
J 0
(1325 4900);
PAINT ORANGE (1325 4900);
DISPLAY INVISIBLE (1325 4900);
FORCEADD RES..2
(1325 4650);
FORCEPROP 1 LAST PACK_TYPE 0402
J 0
(1365 4475);
DISPLAY 0.617021 (1365 4475);
PAINT SKYBLUE (1365 4475);
FORCEPROP 1 LAST MATERIAL CHIP
J 0
(1365 4575);
DISPLAY 0.617021 (1365 4575);
PAINT SKYBLUE (1365 4575);
FORCEPROP 1 LASTPIN (1325 4550) $PN 2
J 0
(1330 4560);
DISPLAY 0.617021 (1330 4560);
PAINT ORANGE (1330 4560);
FORCEPROP 1 LASTPIN (1325 4750) $PN 1
J 0
(1330 4712);
DISPLAY 0.617021 (1330 4712);
PAINT ORANGE (1330 4712);
FORCEPROP 1 LAST LOCATION R3P44
J 0
(1370 4775);
DISPLAY 0.617021 (1370 4775);
PAINT AQUA (1370 4775);
FORCEPROP 1 LAST TOLERANCE 1%
J 0
(1370 4675);
DISPLAY 0.617021 (1370 4675);
PAINT SKYBLUE (1370 4675);
FORCEPROP 1 LAST VALUE 4.75K
J 0
(1370 4725);
DISPLAY 0.617021 (1370 4725);
PAINT SKYBLUE (1370 4725);
FORCEPROP 1 LAST WATTAGE 1/16W
J 0
(1365 4625);
DISPLAY 0.617021 (1365 4625);
PAINT SKYBLUE (1365 4625);
FORCEPROP 1 LAST PART_NUMBER G21796-072
J 0
(1365 4525);
DISPLAY 0.617021 (1365 4525);
PAINT BLUE (1365 4525);
FORCEPROP 2 LAST CDS_LIB mstr_discrete
J 0
(1325 4650);
PAINT ORANGE (1325 4650);
DISPLAY INVISIBLE (1325 4650);
FORCEPROP 2 LAST CDS_LOCATION R3P44
J 0
(1370 4775);
DISPLAY 0.617021 (1370 4775);
PAINT AQUA (1370 4775);
DISPLAY INVISIBLE (1370 4775);
FORCEPROP 2 LAST ROOM V_SUPER
J 0
(1375 4825);
DISPLAY 1.021277 (1375 4825);
PAINT ORANGE (1375 4825);
DISPLAY INVISIBLE (1375 4825);
FORCEPROP 1 LAST PATH I59
J 0
(1375 4825);
DISPLAY 0.978723 (1375 4825);
PAINT WHITE (1375 4825);
DISPLAY INVISIBLE (1375 4825);
FORCEPROP 2 LAST SEC_TYPE 0402
J 0
(1375 4875);
DISPLAY 1.021277 (1375 4875);
PAINT ORANGE (1375 4875);
DISPLAY INVISIBLE (1375 4875);
FORCEPROP 2 LAST SEC 1
J 0
(1375 4875);
DISPLAY 0.680851 (1375 4875);
PAINT MONO (1375 4875);
DISPLAY INVISIBLE (1375 4875);
FORCEADD CAP..1
(1225 4050);
FORCEPROP 1 LASTPIN (1225 3950) $PN 2
J 0
(1235 3930);
DISPLAY 0.617021 (1235 3930);
PAINT ORANGE (1235 3930);
FORCEPROP 1 LAST MATERIAL X7R
J 0
(1275 3950);
DISPLAY 0.617021 (1275 3950);
PAINT SKYBLUE (1275 3950);
FORCEPROP 1 LAST VOLTAGE 25V
J 0
(1275 4050);
DISPLAY 0.617021 (1275 4050);
PAINT SKYBLUE (1275 4050);
FORCEPROP 1 LAST PACK_TYPE 0402
J 0
(1275 3850);
DISPLAY 0.617021 (1275 3850);
PAINT SKYBLUE (1275 3850);
FORCEPROP 1 LAST TOLERANCE 10%
J 0
(1275 4000);
DISPLAY 0.617021 (1275 4000);
PAINT SKYBLUE (1275 4000);
FORCEPROP 1 LAST PART_NUMBER A36096-090
J 0
(1275 3900);
DISPLAY 0.617021 (1275 3900);
PAINT BLUE (1275 3900);
FORCEPROP 1 LASTPIN (1225 4150) $PN 1
J 0
(1235 4130);
DISPLAY 0.617021 (1235 4130);
PAINT ORANGE (1235 4130);
FORCEPROP 1 LAST VALUE 0.047UF
J 0
(1275 4100);
DISPLAY 0.617021 (1275 4100);
PAINT SKYBLUE (1275 4100);
FORCEPROP 1 LAST LOCATION C3P45
J 0
(1275 4150);
DISPLAY 0.617021 (1275 4150);
PAINT AQUA (1275 4150);
FORCEPROP 2 LAST CDS_LIB mstr_discrete
J 0
(1225 4050);
PAINT ORANGE (1225 4050);
DISPLAY INVISIBLE (1225 4050);
FORCEPROP 2 LAST ROOM V_SUPER
J 0
(1275 4200);
DISPLAY 1.021277 (1275 4200);
PAINT ORANGE (1275 4200);
DISPLAY INVISIBLE (1275 4200);
FORCEPROP 1 LAST PATH I60
J 0
(1275 4200);
DISPLAY 0.978723 (1275 4200);
PAINT WHITE (1275 4200);
DISPLAY INVISIBLE (1275 4200);
FORCEPROP 2 LAST SEC_TYPE 0402
J 0
(1275 4250);
DISPLAY 1.021277 (1275 4250);
PAINT ORANGE (1275 4250);
DISPLAY INVISIBLE (1275 4250);
FORCEPROP 2 LAST SEC 1
J 0
(1275 4250);
DISPLAY 0.680851 (1275 4250);
PAINT MONO (1275 4250);
DISPLAY INVISIBLE (1275 4250);
FORCEPROP 2 LAST CDS_LOCATION C3P45
J 0
(1275 4150);
DISPLAY 0.617021 (1275 4150);
PAINT AQUA (1275 4150);
DISPLAY INVISIBLE (1275 4150);
FORCEADD GND..1
(1125 4100);
FORCEPROP 3 LASTPIN (1125 4150) SIG_NAME GND\g
J 0
(1135 4160);
DISPLAY 0.659574 (1135 4160);
PAINT MONO (1135 4160);
DISPLAY INVISIBLE (1135 4160);
FORCEPROP 1 LAST VOLTAGE 0.0V
J 0
(1080 4057);
DISPLAY 0.340426 (1080 4057);
PAINT SKYBLUE (1080 4057);
DISPLAY INVISIBLE (1080 4057);
FORCEPROP 1 LAST BODY_TYPE PLUMBING
J 0
(1080 4057);
DISPLAY 0.340426 (1080 4057);
PAINT GREEN (1080 4057);
DISPLAY INVISIBLE (1080 4057);
FORCEPROP 1 LAST SIZE 1B
J 0
(1200 4050);
DISPLAY 0.872340 (1200 4050);
PAINT AQUA (1200 4050);
DISPLAY INVISIBLE (1200 4050);
FORCEPROP 2 LAST CDS_LIB mstr_symbols
J 0
(1125 4100);
PAINT ORANGE (1125 4100);
DISPLAY INVISIBLE (1125 4100);
FORCEPROP 1 LAST HDL_POWER GND
J 0
(1125 4250);
DISPLAY 0.872340 (1125 4250);
PAINT GREEN (1125 4250);
DISPLAY INVISIBLE (1125 4250);
FORCEPROP 1 LAST PATH I61
J 0
(1200 4100);
DISPLAY 0.872340 (1200 4100);
PAINT AQUA (1200 4100);
DISPLAY INVISIBLE (1200 4100);
FORCEADD GND..1
(1225 3850);
FORCEPROP 3 LASTPIN (1225 3900) SIG_NAME GND\g
J 0
(1235 3910);
DISPLAY 0.659574 (1235 3910);
PAINT MONO (1235 3910);
DISPLAY INVISIBLE (1235 3910);
FORCEPROP 1 LAST VOLTAGE 0.0V
J 0
(1180 3807);
DISPLAY 0.340426 (1180 3807);
PAINT SKYBLUE (1180 3807);
DISPLAY INVISIBLE (1180 3807);
FORCEPROP 1 LAST BODY_TYPE PLUMBING
J 0
(1180 3807);
DISPLAY 0.340426 (1180 3807);
PAINT GREEN (1180 3807);
DISPLAY INVISIBLE (1180 3807);
FORCEPROP 2 LAST CDS_LIB mstr_symbols
J 0
(1225 3850);
PAINT ORANGE (1225 3850);
DISPLAY INVISIBLE (1225 3850);
FORCEPROP 1 LAST HDL_POWER GND
J 0
(1225 4000);
DISPLAY 0.872340 (1225 4000);
PAINT GREEN (1225 4000);
DISPLAY INVISIBLE (1225 4000);
FORCEPROP 1 LAST SIZE 1B
J 0
(1300 3800);
DISPLAY 0.872340 (1300 3800);
PAINT AQUA (1300 3800);
DISPLAY INVISIBLE (1300 3800);
FORCEPROP 1 LAST PATH I62
J 0
(1300 3850);
DISPLAY 0.872340 (1300 3850);
PAINT AQUA (1300 3850);
DISPLAY INVISIBLE (1300 3850);
FORCEADD OFFPAGE..2
(1850 2000);
FORCEPROP 2 LAST $XR0 190 
J 0
(2039 2000);
DISPLAY 0.638298 (2039 2000);
PAINT MONO (2039 2000);
FORCEPROP 2 LASTPIN (1800 2000) SIG_NAME PWRGD_P5V
J 2
(1790 2010);
DISPLAY 0.617021 (1790 2010);
PAINT ORANGE (1790 2010);
FORCEPROP 2 LAST CDS_LIB mstr_standard
J 0
(1850 2000);
PAINT ORANGE (1850 2000);
DISPLAY INVISIBLE (1850 2000);
FORCEPROP 1 LAST COMMENT_BODY TRUE
J 0
(1805 1905);
DISPLAY 0.872340 (1805 1905);
PAINT GREEN (1805 1905);
DISPLAY INVISIBLE (1805 1905);
FORCEPROP 2 LAST PATH I63
J 0
(2025 2075);
DISPLAY 1.021277 (2025 2075);
PAINT ORANGE (2025 2075);
DISPLAY INVISIBLE (2025 2075);
FORCEPROP 1 LAST OFFPAGE TRUE
J 0
(2175 1875);
DISPLAY 0.872340 (2175 1875);
PAINT GREEN (2175 1875);
DISPLAY INVISIBLE (2175 1875);
FORCEADD OFFPAGE..2
(1850 1250);
FORCEPROP 2 LAST $XR0 175 
J 0
(2039 1250);
DISPLAY 0.638298 (2039 1250);
PAINT MONO (2039 1250);
FORCEPROP 2 LAST $XR1 190 
J 0
(2159 1250);
DISPLAY 0.638298 (2159 1250);
PAINT MONO (2159 1250);
FORCEPROP 2 LASTPIN (1800 1250) SIG_NAME PWRGD_P3V3
J 2
(1790 1260);
DISPLAY 0.617021 (1790 1260);
PAINT ORANGE (1790 1260);
FORCEPROP 1 LAST COMMENT_BODY TRUE
J 0
(1805 1155);
DISPLAY 0.872340 (1805 1155);
PAINT GREEN (1805 1155);
DISPLAY INVISIBLE (1805 1155);
FORCEPROP 2 LAST CDS_LIB mstr_standard
J 0
(1850 1250);
PAINT ORANGE (1850 1250);
DISPLAY INVISIBLE (1850 1250);
FORCEPROP 2 LAST PATH I64
J 0
(2025 1325);
DISPLAY 1.021277 (2025 1325);
PAINT ORANGE (2025 1325);
DISPLAY INVISIBLE (2025 1325);
FORCEPROP 1 LAST OFFPAGE TRUE
J 0
(2175 1125);
DISPLAY 0.872340 (2175 1125);
PAINT GREEN (2175 1125);
DISPLAY INVISIBLE (2175 1125);
FORCEADD RES..1
(1350 2000);
FORCEPROP 1 LASTPIN (1250 2000) $PN 1
J 0
(1262 2012);
DISPLAY 0.617021 (1262 2012);
PAINT ORANGE (1262 2012);
FORCEPROP 1 LAST WATTAGE 1/16W
J 2
(1325 1850);
DISPLAY 0.617021 (1325 1850);
PAINT SKYBLUE (1325 1850);
FORCEPROP 1 LAST VALUE 100.0
J 2
(1325 1900);
DISPLAY 0.617021 (1325 1900);
PAINT SKYBLUE (1325 1900);
FORCEPROP 1 LAST TOLERANCE 1%
J 0
(1350 1900);
DISPLAY 0.617021 (1350 1900);
PAINT SKYBLUE (1350 1900);
FORCEPROP 1 LAST MATERIAL CHIP
J 0
(1350 1850);
DISPLAY 0.617021 (1350 1850);
PAINT SKYBLUE (1350 1850);
FORCEPROP 1 LASTPIN (1450 2000) $PN 2
J 0
(1412 2012);
DISPLAY 0.617021 (1412 2012);
PAINT ORANGE (1412 2012);
FORCEPROP 1 LAST PACK_TYPE 0402
J 0
(1600 1850);
DISPLAY 0.617021 (1600 1850);
PAINT SKYBLUE (1600 1850);
FORCEPROP 1 LAST LOCATION R2P20
J 0
(1300 2050);
DISPLAY 0.617021 (1300 2050);
PAINT AQUA (1300 2050);
FORCEPROP 1 LAST PART_NUMBER G21796-017
J 0
(1300 2100);
DISPLAY 0.617021 (1300 2100);
PAINT BLUE (1300 2100);
FORCEPROP 2 LAST CDS_LIB mstr_discrete
J 0
(1350 2000);
PAINT ORANGE (1350 2000);
DISPLAY INVISIBLE (1350 2000);
FORCEPROP 0 LAST ROOM V_SUPER
J 0
(1300 2200);
DISPLAY 1.021277 (1300 2200);
PAINT ORANGE (1300 2200);
DISPLAY INVISIBLE (1300 2200);
FORCEPROP 1 LAST PATH I65
J 0
(1300 2150);
DISPLAY 0.978723 (1300 2150);
PAINT WHITE (1300 2150);
DISPLAY INVISIBLE (1300 2150);
FORCEPROP 2 LAST SEC_TYPE 0402
J 0
(1300 2200);
DISPLAY 1.021277 (1300 2200);
PAINT ORANGE (1300 2200);
DISPLAY INVISIBLE (1300 2200);
FORCEPROP 2 LAST SEC 1
J 0
(1300 2200);
DISPLAY 0.680851 (1300 2200);
PAINT MONO (1300 2200);
DISPLAY INVISIBLE (1300 2200);
FORCEADD RES..1
(1300 1250);
FORCEPROP 1 LAST WATTAGE 1/16W
J 2
(1275 1100);
DISPLAY 0.617021 (1275 1100);
PAINT SKYBLUE (1275 1100);
FORCEPROP 1 LAST VALUE 49.9
J 2
(1275 1150);
DISPLAY 0.617021 (1275 1150);
PAINT SKYBLUE (1275 1150);
FORCEPROP 1 LASTPIN (1200 1250) $PN 1
J 0
(1212 1262);
DISPLAY 0.617021 (1212 1262);
PAINT ORANGE (1212 1262);
FORCEPROP 1 LAST LOCATION R1L16
J 0
(1250 1300);
DISPLAY 0.617021 (1250 1300);
PAINT AQUA (1250 1300);
FORCEPROP 1 LASTPIN (1400 1250) $PN 2
J 0
(1362 1262);
DISPLAY 0.617021 (1362 1262);
PAINT ORANGE (1362 1262);
FORCEPROP 1 LAST TOLERANCE 1%
J 0
(1300 1150);
DISPLAY 0.617021 (1300 1150);
PAINT SKYBLUE (1300 1150);
FORCEPROP 1 LAST MATERIAL CHIP
J 0
(1300 1100);
DISPLAY 0.617021 (1300 1100);
PAINT SKYBLUE (1300 1100);
FORCEPROP 1 LAST PART_NUMBER G21796-047
J 0
(1250 1350);
DISPLAY 0.617021 (1250 1350);
PAINT BLUE (1250 1350);
FORCEPROP 1 LAST PACK_TYPE 0402
J 0
(1550 1100);
DISPLAY 0.617021 (1550 1100);
PAINT SKYBLUE (1550 1100);
FORCEPROP 1 LAST PATH I68
J 0
(1250 1400);
DISPLAY 0.978723 (1250 1400);
PAINT WHITE (1250 1400);
DISPLAY INVISIBLE (1250 1400);
FORCEPROP 0 LAST ROOM V_SUPER
J 0
(1250 1450);
DISPLAY 1.021277 (1250 1450);
PAINT ORANGE (1250 1450);
DISPLAY INVISIBLE (1250 1450);
FORCEPROP 2 LAST CDS_LOCATION R1L16
J 0
(1250 1300);
DISPLAY 0.617021 (1250 1300);
PAINT AQUA (1250 1300);
DISPLAY INVISIBLE (1250 1300);
FORCEPROP 2 LAST SEC 1
J 0
(1250 1450);
DISPLAY 0.680851 (1250 1450);
PAINT MONO (1250 1450);
DISPLAY INVISIBLE (1250 1450);
FORCEPROP 2 LAST SEC_TYPE 0402
J 0
(1250 1450);
DISPLAY 1.021277 (1250 1450);
PAINT ORANGE (1250 1450);
DISPLAY INVISIBLE (1250 1450);
FORCEPROP 2 LAST CDS_LIB mstr_discrete
J 0
(1300 1250);
PAINT ORANGE (1300 1250);
DISPLAY INVISIBLE (1300 1250);
FORCEADD P3V3_STBY..1
(275 4900);
FORCEPROP 3 LASTPIN (275 4850) SIG_NAME P3V3_STBY\g
J 0
(285 4860);
DISPLAY 0.659574 (285 4860);
PAINT MONO (285 4860);
DISPLAY INVISIBLE (285 4860);
FORCEPROP 1 LAST HDL_POWER P3V3_STBY
J 0
(-25 4775);
DISPLAY 0.872340 (-25 4775);
PAINT ORANGE (-25 4775);
DISPLAY INVISIBLE (-25 4775);
FORCEPROP 1 LAST BODY_TYPE PLUMBING
J 0
(230 4857);
DISPLAY 0.340426 (230 4857);
PAINT GREEN (230 4857);
DISPLAY INVISIBLE (230 4857);
FORCEPROP 1 LAST VOLTAGE 3.3V
J 0
(230 4857);
DISPLAY 0.340426 (230 4857);
PAINT SKYBLUE (230 4857);
DISPLAY INVISIBLE (230 4857);
FORCEPROP 1 LAST PATH I69
J 0
(320 4902);
DISPLAY 0.340426 (320 4902);
PAINT GREEN (320 4902);
DISPLAY INVISIBLE (320 4902);
FORCEPROP 2 LAST CDS_LIB mstr_symbols
J 0
(275 4900);
PAINT ORANGE (275 4900);
DISPLAY INVISIBLE (275 4900);
FORCEPROP 1 LAST SIZE 1B
J 0
(320 4922);
DISPLAY 0.340426 (320 4922);
PAINT GREEN (320 4922);
DISPLAY INVISIBLE (320 4922);
FORCEADD ADM1085..1
(725 4400);
FORCEPROP 2 LASTPIN (375 4450) $PN 3
J 2
(365 4460);
DISPLAY 0.617021 (365 4460);
PAINT ORANGE (365 4460);
FORCEPROP 2 LASTPIN (375 4500) $PN 6
J 2
(365 4510);
DISPLAY 0.617021 (365 4510);
PAINT ORANGE (365 4510);
FORCEPROP 2 LASTPIN (375 4350) $PN 1
J 2
(365 4360);
DISPLAY 0.617021 (365 4360);
PAINT ORANGE (365 4360);
FORCEPROP 1 LAST MATERIAL IC
J 0
(425 4700);
DISPLAY 0.617021 (425 4700);
PAINT SKYBLUE (425 4700);
FORCEPROP 1 LAST PART_NUMBER H46130-001
J 0
(425 4100);
DISPLAY 0.617021 (425 4100);
PAINT BLUE (425 4100);
FORCEPROP 1 LAST LOCATION U7D3
J 0
(425 4750);
DISPLAY 0.617021 (425 4750);
PAINT AQUA (425 4750);
FORCEPROP 2 LASTPIN (1075 4200) $PN 2
J 0
(1085 4210);
DISPLAY 0.617021 (1085 4210);
PAINT ORANGE (1085 4210);
FORCEPROP 2 LASTPIN (1075 4250) $PN 5
J 0
(1085 4260);
DISPLAY 0.617021 (1085 4260);
PAINT ORANGE (1085 4260);
FORCEPROP 2 LASTPIN (1075 4350) $PN 4
J 0
(1085 4360);
DISPLAY 0.617021 (1085 4360);
PAINT ORANGE (1085 4360);
FORCEPROP 2 LAST ROOM V_SUPER
J 0
(425 4800);
DISPLAY 1.021277 (425 4800);
PAINT ORANGE (425 4800);
DISPLAY INVISIBLE (425 4800);
FORCEPROP 2 LAST CDS_LOCATION U7D3
J 0
(425 4750);
DISPLAY 0.617021 (425 4750);
PAINT AQUA (425 4750);
DISPLAY INVISIBLE (425 4750);
FORCEPROP 2 LAST SEC 1
J 0
(425 4800);
DISPLAY 0.680851 (425 4800);
PAINT MONO (425 4800);
DISPLAY INVISIBLE (425 4800);
FORCEPROP 2 LAST SEC_TYPE SMT
J 0
(425 4800);
DISPLAY 1.021277 (425 4800);
PAINT ORANGE (425 4800);
DISPLAY INVISIBLE (425 4800);
FORCEPROP 1 LAST PACK_TYPE SMT
J 0
(425 4800);
PAINT SKYBLUE (425 4800);
DISPLAY INVISIBLE (425 4800);
FORCEPROP 1 LAST PATH I70
J 0
(725 4700);
PAINT GREEN (725 4700);
DISPLAY INVISIBLE (725 4700);
FORCEPROP 2 LAST CDS_LIB mstr_analog
J 0
(725 4400);
PAINT ORANGE (725 4400);
DISPLAY INVISIBLE (725 4400);
FORCEADD RES..2
(-25 4750);
FORCEPROP 1 LASTPIN (-25 4650) $PN 2
J 0
(-20 4660);
DISPLAY 0.617021 (-20 4660);
PAINT ORANGE (-20 4660);
FORCEPROP 1 LASTPIN (-25 4850) $PN 1
J 0
(-20 4812);
DISPLAY 0.617021 (-20 4812);
PAINT ORANGE (-20 4812);
FORCEPROP 1 LAST PACK_TYPE 0402
J 0
(15 4575);
DISPLAY 0.617021 (15 4575);
PAINT SKYBLUE (15 4575);
FORCEPROP 1 LAST TOLERANCE 1%
J 0
(20 4775);
DISPLAY 0.617021 (20 4775);
PAINT SKYBLUE (20 4775);
FORCEPROP 1 LAST WATTAGE 1/16W
J 0
(15 4725);
DISPLAY 0.617021 (15 4725);
PAINT SKYBLUE (15 4725);
FORCEPROP 1 LAST VALUE 10.0K
J 0
(20 4825);
DISPLAY 0.617021 (20 4825);
PAINT SKYBLUE (20 4825);
FORCEPROP 1 LAST MATERIAL EMPTY
J 0
(15 4675);
DISPLAY 0.617021 (15 4675);
PAINT RED (15 4675);
FORCEPROP 1 LAST LOCATION R3P50
J 0
(20 4875);
DISPLAY 0.617021 (20 4875);
PAINT AQUA (20 4875);
FORCEPROP 1 LAST PART_NUMBER G21796-016
J 0
(15 4625);
DISPLAY 0.617021 (15 4625);
PAINT BLUE (15 4625);
FORCEPROP 2 LAST CDS_LIB mstr_discrete
J 0
(-25 4750);
PAINT ORANGE (-25 4750);
DISPLAY INVISIBLE (-25 4750);
FORCEPROP 2 LAST ROOM V_SUPER
J 0
(25 4925);
DISPLAY 1.021277 (25 4925);
PAINT ORANGE (25 4925);
DISPLAY INVISIBLE (25 4925);
FORCEPROP 1 LAST PATH I71
J 0
(25 4925);
DISPLAY 0.978723 (25 4925);
PAINT WHITE (25 4925);
DISPLAY INVISIBLE (25 4925);
FORCEPROP 2 LAST SEC_TYPE 0402
J 0
(25 4975);
DISPLAY 1.021277 (25 4975);
PAINT ORANGE (25 4975);
DISPLAY INVISIBLE (25 4975);
FORCEPROP 2 LAST SEC 1
J 0
(25 4975);
DISPLAY 0.680851 (25 4975);
PAINT MONO (25 4975);
DISPLAY INVISIBLE (25 4975);
FORCEPROP 2 LAST CDS_LOCATION R3P50
J 0
(20 4875);
DISPLAY 0.617021 (20 4875);
PAINT AQUA (20 4875);
DISPLAY INVISIBLE (20 4875);
FORCEADD CAP_A..1
(275 3950);
FORCEPROP 1 LAST PACK_TYPE 0402V
J 0
(325 3750);
DISPLAY 0.617021 (325 3750);
PAINT SKYBLUE (325 3750);
FORCEPROP 1 LASTPIN (275 3850) $PN 2
J 0
(285 3830);
DISPLAY 0.617021 (285 3830);
PAINT ORANGE (285 3830);
FORCEPROP 1 LASTPIN (275 4050) $PN 1
J 0
(285 4030);
DISPLAY 0.617021 (285 4030);
PAINT ORANGE (285 4030);
FORCEPROP 1 LAST MATERIAL X7R
J 0
(325 3850);
DISPLAY 0.617021 (325 3850);
PAINT SKYBLUE (325 3850);
FORCEPROP 1 LAST VOLTAGE 16V
J 0
(325 3950);
DISPLAY 0.617021 (325 3950);
PAINT SKYBLUE (325 3950);
FORCEPROP 1 LAST TOLERANCE 10%
J 0
(325 3900);
DISPLAY 0.617021 (325 3900);
PAINT SKYBLUE (325 3900);
FORCEPROP 1 LAST VALUE 0.1UF
J 0
(325 4000);
DISPLAY 0.617021 (325 4000);
PAINT SKYBLUE (325 4000);
FORCEPROP 1 LAST LOCATION C3P46
J 0
(325 4050);
DISPLAY 0.617021 (325 4050);
PAINT AQUA (325 4050);
FORCEPROP 1 LAST PART_NUMBER A36096-030
J 0
(325 3800);
DISPLAY 0.617021 (325 3800);
PAINT BLUE (325 3800);
FORCEPROP 2 LAST CDS_LIB dev_discrete
J 0
(275 3950);
PAINT ORANGE (275 3950);
DISPLAY INVISIBLE (275 3950);
FORCEPROP 2 LAST CDS_LOCATION C3P46
J 0
(325 4050);
DISPLAY 0.617021 (325 4050);
PAINT AQUA (325 4050);
DISPLAY INVISIBLE (325 4050);
FORCEPROP 2 LAST ROOM V_SUPER
J 0
(325 4100);
DISPLAY 1.021277 (325 4100);
PAINT ORANGE (325 4100);
DISPLAY INVISIBLE (325 4100);
FORCEPROP 1 LAST PATH I72
J 0
(325 4100);
DISPLAY 0.978723 (325 4100);
PAINT WHITE (325 4100);
DISPLAY INVISIBLE (325 4100);
FORCEPROP 2 LAST SEC_TYPE 0402V
J 0
(325 4150);
DISPLAY 1.021277 (325 4150);
PAINT ORANGE (325 4150);
DISPLAY INVISIBLE (325 4150);
FORCEPROP 2 LAST SEC 1
J 0
(325 4150);
DISPLAY 0.680851 (325 4150);
PAINT MONO (325 4150);
DISPLAY INVISIBLE (325 4150);
FORCEADD GND..1
(275 3750);
FORCEPROP 3 LASTPIN (275 3800) SIG_NAME GND\g
J 0
(285 3810);
DISPLAY 0.659574 (285 3810);
PAINT MONO (285 3810);
DISPLAY INVISIBLE (285 3810);
FORCEPROP 1 LAST VOLTAGE 0.0V
J 0
(230 3707);
DISPLAY 0.340426 (230 3707);
PAINT SKYBLUE (230 3707);
DISPLAY INVISIBLE (230 3707);
FORCEPROP 1 LAST BODY_TYPE PLUMBING
J 0
(230 3707);
DISPLAY 0.340426 (230 3707);
PAINT GREEN (230 3707);
DISPLAY INVISIBLE (230 3707);
FORCEPROP 2 LAST CDS_LIB mstr_symbols
J 0
(275 3750);
PAINT ORANGE (275 3750);
DISPLAY INVISIBLE (275 3750);
FORCEPROP 1 LAST SIZE 1B
J 0
(350 3700);
DISPLAY 0.872340 (350 3700);
PAINT AQUA (350 3700);
DISPLAY INVISIBLE (350 3700);
FORCEPROP 1 LAST PATH I73
J 0
(350 3750);
DISPLAY 0.872340 (350 3750);
PAINT AQUA (350 3750);
DISPLAY INVISIBLE (350 3750);
FORCEPROP 1 LAST HDL_POWER GND
J 0
(275 3900);
DISPLAY 0.872340 (275 3900);
PAINT GREEN (275 3900);
DISPLAY INVISIBLE (275 3900);
FORCEADD RES..2
(-525 4750);
FORCEPROP 1 LASTPIN (-525 4650) $PN 2
J 0
(-520 4660);
DISPLAY 0.617021 (-520 4660);
PAINT ORANGE (-520 4660);
FORCEPROP 1 LASTPIN (-525 4850) $PN 1
J 0
(-520 4812);
DISPLAY 0.617021 (-520 4812);
PAINT ORANGE (-520 4812);
FORCEPROP 1 LAST PACK_TYPE 0402
J 0
(-485 4575);
DISPLAY 0.617021 (-485 4575);
PAINT SKYBLUE (-485 4575);
FORCEPROP 1 LAST WATTAGE 1/16W
J 0
(-485 4725);
DISPLAY 0.617021 (-485 4725);
PAINT SKYBLUE (-485 4725);
FORCEPROP 1 LAST MATERIAL CHIP
J 0
(-485 4675);
DISPLAY 0.617021 (-485 4675);
PAINT SKYBLUE (-485 4675);
FORCEPROP 1 LAST TOLERANCE 1%
J 0
(-480 4775);
DISPLAY 0.617021 (-480 4775);
PAINT SKYBLUE (-480 4775);
FORCEPROP 1 LAST VALUE 90.9K
J 0
(-480 4825);
DISPLAY 0.617021 (-480 4825);
PAINT SKYBLUE (-480 4825);
FORCEPROP 1 LAST LOCATION R3P48
J 0
(-480 4875);
DISPLAY 0.617021 (-480 4875);
PAINT AQUA (-480 4875);
FORCEPROP 1 LAST PART_NUMBER G21796-058
J 0
(-485 4625);
DISPLAY 0.617021 (-485 4625);
PAINT BLUE (-485 4625);
FORCEPROP 2 LAST CDS_LIB mstr_discrete
J 0
(-525 4750);
PAINT ORANGE (-525 4750);
DISPLAY INVISIBLE (-525 4750);
FORCEPROP 2 LAST ROOM V_SUPER
J 0
(-475 4925);
DISPLAY 1.021277 (-475 4925);
PAINT ORANGE (-475 4925);
DISPLAY INVISIBLE (-475 4925);
FORCEPROP 1 LAST PATH I74
J 0
(-475 4925);
DISPLAY 0.978723 (-475 4925);
PAINT WHITE (-475 4925);
DISPLAY INVISIBLE (-475 4925);
FORCEPROP 2 LAST SEC_TYPE 0402
J 0
(-475 4975);
DISPLAY 1.021277 (-475 4975);
PAINT ORANGE (-475 4975);
DISPLAY INVISIBLE (-475 4975);
FORCEPROP 2 LAST SEC 1
J 0
(-475 4975);
DISPLAY 0.680851 (-475 4975);
PAINT MONO (-475 4975);
DISPLAY INVISIBLE (-475 4975);
FORCEPROP 2 LAST CDS_LOCATION R3P48
J 0
(-480 4875);
DISPLAY 0.617021 (-480 4875);
PAINT AQUA (-480 4875);
DISPLAY INVISIBLE (-480 4875);
FORCEADD RES..2
(-525 4250);
FORCEPROP 1 LAST PACK_TYPE 0402
J 0
(-485 4075);
DISPLAY 0.617021 (-485 4075);
PAINT SKYBLUE (-485 4075);
FORCEPROP 1 LASTPIN (-525 4150) $PN 2
J 0
(-520 4160);
DISPLAY 0.617021 (-520 4160);
PAINT ORANGE (-520 4160);
FORCEPROP 1 LASTPIN (-525 4350) $PN 1
J 0
(-520 4312);
DISPLAY 0.617021 (-520 4312);
PAINT ORANGE (-520 4312);
FORCEPROP 1 LAST LOCATION R3P51
J 0
(-480 4375);
DISPLAY 0.617021 (-480 4375);
PAINT AQUA (-480 4375);
FORCEPROP 1 LAST VALUE 6.34K
J 0
(-480 4325);
DISPLAY 0.617021 (-480 4325);
PAINT SKYBLUE (-480 4325);
FORCEPROP 1 LAST TOLERANCE 1%
J 0
(-480 4275);
DISPLAY 0.617021 (-480 4275);
PAINT SKYBLUE (-480 4275);
FORCEPROP 1 LAST MATERIAL CHIP
J 0
(-485 4175);
DISPLAY 0.617021 (-485 4175);
PAINT SKYBLUE (-485 4175);
FORCEPROP 1 LAST WATTAGE 1/16W
J 0
(-485 4225);
DISPLAY 0.617021 (-485 4225);
PAINT SKYBLUE (-485 4225);
FORCEPROP 1 LAST PART_NUMBER G21796-146
J 0
(-485 4125);
DISPLAY 0.617021 (-485 4125);
PAINT BLUE (-485 4125);
FORCEPROP 2 LAST CDS_LIB mstr_discrete
J 0
(-525 4250);
PAINT MONO (-525 4250);
DISPLAY INVISIBLE (-525 4250);
FORCEPROP 2 LAST CDS_LOCATION R3P51
J 0
(-480 4375);
DISPLAY 0.617021 (-480 4375);
PAINT AQUA (-480 4375);
DISPLAY INVISIBLE (-480 4375);
FORCEPROP 2 LAST SEC 1
J 0
(-475 4475);
PAINT MONO (-475 4475);
DISPLAY INVISIBLE (-475 4475);
FORCEPROP 2 LAST SEC_TYPE 0402
J 0
(-475 4475);
DISPLAY 1.021277 (-475 4475);
PAINT ORANGE (-475 4475);
DISPLAY INVISIBLE (-475 4475);
FORCEPROP 1 LAST PATH I75
J 0
(-475 4425);
DISPLAY 0.978723 (-475 4425);
PAINT WHITE (-475 4425);
DISPLAY INVISIBLE (-475 4425);
FORCEPROP 2 LAST ROOM V_SUPER
J 0
(-475 4425);
DISPLAY 1.021277 (-475 4425);
PAINT ORANGE (-475 4425);
DISPLAY INVISIBLE (-475 4425);
FORCEADD GND..1
(-525 4050);
FORCEPROP 3 LASTPIN (-525 4100) SIG_NAME GND\g
J 0
(-515 4110);
DISPLAY 0.659574 (-515 4110);
PAINT MONO (-515 4110);
DISPLAY INVISIBLE (-515 4110);
FORCEPROP 1 LAST BODY_TYPE PLUMBING
J 0
(-570 4007);
DISPLAY 0.340426 (-570 4007);
PAINT GREEN (-570 4007);
DISPLAY INVISIBLE (-570 4007);
FORCEPROP 2 LAST CDS_LIB mstr_symbols
J 0
(-525 4050);
PAINT ORANGE (-525 4050);
DISPLAY INVISIBLE (-525 4050);
FORCEPROP 1 LAST VOLTAGE 0.0V
J 0
(-570 4007);
DISPLAY 0.340426 (-570 4007);
PAINT SKYBLUE (-570 4007);
DISPLAY INVISIBLE (-570 4007);
FORCEPROP 1 LAST SIZE 1B
J 0
(-450 4000);
DISPLAY 0.872340 (-450 4000);
PAINT AQUA (-450 4000);
DISPLAY INVISIBLE (-450 4000);
FORCEPROP 1 LAST PATH I76
J 0
(-450 4050);
DISPLAY 0.872340 (-450 4050);
PAINT AQUA (-450 4050);
DISPLAY INVISIBLE (-450 4050);
FORCEPROP 1 LAST HDL_POWER GND
J 0
(-525 4200);
DISPLAY 0.872340 (-525 4200);
PAINT GREEN (-525 4200);
DISPLAY INVISIBLE (-525 4200);
FORCEADD ADM809..1
(200 1350);
FORCEPROP 2 LASTPIN (0 1400) $PN 3
J 2
(-10 1410);
DISPLAY 0.617021 (-10 1410);
PAINT ORANGE (-10 1410);
FORCEPROP 1 LAST POWER_GROUP GND=GND;
J 0
(50 1000);
DISPLAY 0.617021 (50 1000);
PAINT ORANGE (50 1000);
FORCEPROP 2 LASTPIN (400 1250) $PN 2
J 0
(410 1260);
DISPLAY 0.617021 (410 1260);
PAINT ORANGE (410 1260);
FORCEPROP 1 LAST PART_NUMBER D23047-001
J 0
(55 1055);
DISPLAY 0.617021 (55 1055);
PAINT BLUE (55 1055);
FORCEPROP 1 LAST LOCATION U1L3
J 0
(55 1609);
DISPLAY 0.617021 (55 1609);
PAINT AQUA (55 1609);
FORCEPROP 1 LAST MATERIAL IC
J 0
(55 1568);
DISPLAY 0.617021 (55 1568);
PAINT SKYBLUE (55 1568);
FORCEPROP 2 LAST CDS_LIB mstr_analog
J 0
(200 1350);
PAINT ORANGE (200 1350);
DISPLAY INVISIBLE (200 1350);
FORCEPROP 2 LAST CDS_LOCATION U1L3
J 0
(55 1609);
DISPLAY 0.617021 (55 1609);
PAINT AQUA (55 1609);
DISPLAY INVISIBLE (55 1609);
FORCEPROP 2 LAST $SEC 1
J 0
(75 1650);
DISPLAY 0.680851 (75 1650);
PAINT MONO (75 1650);
DISPLAY INVISIBLE (75 1650);
FORCEPROP 1 LAST PACK_TYPE SMLF
J 0
(55 1650);
DISPLAY 0.872340 (55 1650);
PAINT SKYBLUE (55 1650);
DISPLAY INVISIBLE (55 1650);
FORCEPROP 2 LAST CDS_SEC 1
J 0
(75 1650);
DISPLAY 1.021277 (75 1650);
PAINT ORANGE (75 1650);
DISPLAY INVISIBLE (75 1650);
FORCEPROP 2 LAST ROOM V_SUPER
J 0
(75 1650);
DISPLAY 1.021277 (75 1650);
PAINT ORANGE (75 1650);
DISPLAY INVISIBLE (75 1650);
FORCEPROP 1 LAST PATH I80
J 0
(455 1560);
DISPLAY 0.872340 (455 1560);
PAINT PURPLE (455 1560);
DISPLAY INVISIBLE (455 1560);
FORCEADD CAP_A..1
(-300 1250);
FORCEPROP 1 LAST MATERIAL X7R
J 0
(-250 1150);
DISPLAY 0.617021 (-250 1150);
PAINT SKYBLUE (-250 1150);
FORCEPROP 1 LAST VOLTAGE 16V
J 0
(-250 1250);
DISPLAY 0.617021 (-250 1250);
PAINT SKYBLUE (-250 1250);
FORCEPROP 1 LAST PACK_TYPE 0402V
J 0
(-250 1050);
DISPLAY 0.617021 (-250 1050);
PAINT SKYBLUE (-250 1050);
FORCEPROP 1 LAST TOLERANCE 10%
J 0
(-250 1200);
DISPLAY 0.617021 (-250 1200);
PAINT SKYBLUE (-250 1200);
FORCEPROP 1 LAST VALUE 0.1UF
J 0
(-250 1300);
DISPLAY 0.617021 (-250 1300);
PAINT SKYBLUE (-250 1300);
FORCEPROP 1 LAST LOCATION C1L16
J 0
(-250 1350);
DISPLAY 0.617021 (-250 1350);
PAINT AQUA (-250 1350);
FORCEPROP 1 LAST PART_NUMBER A36096-030
J 0
(-250 1100);
DISPLAY 0.617021 (-250 1100);
PAINT BLUE (-250 1100);
FORCEPROP 1 LASTPIN (-300 1150) $PN 2
J 0
(-290 1130);
DISPLAY 0.787234 (-290 1130);
PAINT ORANGE (-290 1130);
DISPLAY INVISIBLE (-290 1130);
FORCEPROP 2 LAST CDS_LIB dev_discrete
J 0
(-300 1250);
PAINT ORANGE (-300 1250);
DISPLAY INVISIBLE (-300 1250);
FORCEPROP 1 LASTPIN (-300 1350) $PN 1
J 0
(-290 1330);
DISPLAY 0.787234 (-290 1330);
PAINT ORANGE (-290 1330);
DISPLAY INVISIBLE (-290 1330);
FORCEPROP 2 LAST ROOM V_SUPER
J 0
(-250 1400);
DISPLAY 1.021277 (-250 1400);
PAINT ORANGE (-250 1400);
DISPLAY INVISIBLE (-250 1400);
FORCEPROP 1 LAST PATH I81
J 0
(-250 1400);
DISPLAY 0.978723 (-250 1400);
PAINT WHITE (-250 1400);
DISPLAY INVISIBLE (-250 1400);
FORCEPROP 2 LAST CDS_LOCATION C1L16
J 0
(-250 1350);
DISPLAY 0.617021 (-250 1350);
PAINT AQUA (-250 1350);
DISPLAY INVISIBLE (-250 1350);
FORCEADD GND..1
(-300 1050);
FORCEPROP 3 LASTPIN (-300 1100) SIG_NAME GND\g
J 0
(-290 1110);
DISPLAY 0.659574 (-290 1110);
PAINT MONO (-290 1110);
DISPLAY INVISIBLE (-290 1110);
FORCEPROP 1 LAST BODY_TYPE PLUMBING
J 0
(-345 1007);
DISPLAY 0.340426 (-345 1007);
PAINT GREEN (-345 1007);
DISPLAY INVISIBLE (-345 1007);
FORCEPROP 1 LAST VOLTAGE 0.0V
J 0
(-345 1007);
DISPLAY 0.340426 (-345 1007);
PAINT SKYBLUE (-345 1007);
DISPLAY INVISIBLE (-345 1007);
FORCEPROP 1 LAST SIZE 1B
J 0
(-225 1000);
DISPLAY 0.872340 (-225 1000);
PAINT AQUA (-225 1000);
DISPLAY INVISIBLE (-225 1000);
FORCEPROP 2 LAST CDS_LIB mstr_symbols
J 0
(-300 1050);
PAINT ORANGE (-300 1050);
DISPLAY INVISIBLE (-300 1050);
FORCEPROP 1 LAST HDL_POWER GND
J 0
(-300 1200);
DISPLAY 0.872340 (-300 1200);
PAINT GREEN (-300 1200);
DISPLAY INVISIBLE (-300 1200);
FORCEPROP 1 LAST PATH I82
J 0
(-225 1050);
DISPLAY 0.872340 (-225 1050);
PAINT AQUA (-225 1050);
DISPLAY INVISIBLE (-225 1050);
FORCEADD P3V3..1
(-300 1500);
FORCEPROP 3 LASTPIN (-300 1450) SIG_NAME P3V3\g
J 0
(-290 1460);
DISPLAY 0.659574 (-290 1460);
PAINT MONO (-290 1460);
DISPLAY INVISIBLE (-290 1460);
FORCEPROP 1 LAST HDL_POWER P3V3
J 0
(-625 1375);
DISPLAY 0.872340 (-625 1375);
PAINT ORANGE (-625 1375);
DISPLAY INVISIBLE (-625 1375);
FORCEPROP 1 LAST BODY_TYPE PLUMBING
J 0
(-345 1457);
DISPLAY 0.340426 (-345 1457);
PAINT GREEN (-345 1457);
DISPLAY INVISIBLE (-345 1457);
FORCEPROP 1 LAST VOLTAGE 3.3V
J 0
(-345 1457);
DISPLAY 0.340426 (-345 1457);
PAINT SKYBLUE (-345 1457);
DISPLAY INVISIBLE (-345 1457);
FORCEPROP 1 LAST PATH I83
J 0
(-255 1502);
DISPLAY 0.340426 (-255 1502);
PAINT GREEN (-255 1502);
DISPLAY INVISIBLE (-255 1502);
FORCEPROP 2 LAST CDS_LIB mstr_symbols
J 0
(-300 1500);
PAINT ORANGE (-300 1500);
DISPLAY INVISIBLE (-300 1500);
FORCEPROP 1 LAST SIZE 1B
J 0
(-255 1522);
DISPLAY 0.340426 (-255 1522);
PAINT GREEN (-255 1522);
DISPLAY INVISIBLE (-255 1522);
FORCEADD OFFPAGE..2
(2025 4350);
FORCEPROP 2 LAST $XR0 200 
J 0
(2214 4350);
DISPLAY 0.638298 (2214 4350);
PAINT MONO (2214 4350);
FORCEPROP 2 LAST $XR1 118 
J 0
(2334 4350);
DISPLAY 0.638298 (2334 4350);
PAINT MONO (2334 4350);
FORCEPROP 2 LAST $XR2 157 
J 0
(2454 4350);
DISPLAY 0.638298 (2454 4350);
PAINT MONO (2454 4350);
FORCEPROP 2 LAST $XR3 183 
J 0
(2214 4314);
DISPLAY 0.638298 (2214 4314);
PAINT MONO (2214 4314);
FORCEPROP 2 LAST $XR4 191 
J 0
(2334 4314);
DISPLAY 0.638298 (2334 4314);
PAINT MONO (2334 4314);
FORCEPROP 2 LASTPIN (1975 4350) SIG_NAME PWRGD_DSW_PWROK
J 2
(1965 4360);
DISPLAY 0.617021 (1965 4360);
PAINT ORANGE (1965 4360);
FORCEPROP 2 LAST CDS_LIB mstr_standard
J 0
(2025 4350);
PAINT ORANGE (2025 4350);
DISPLAY INVISIBLE (2025 4350);
FORCEPROP 1 LAST COMMENT_BODY TRUE
J 0
(1980 4255);
DISPLAY 0.872340 (1980 4255);
PAINT GREEN (1980 4255);
DISPLAY INVISIBLE (1980 4255);
FORCEPROP 1 LAST OFFPAGE TRUE
J 0
(2350 4225);
DISPLAY 0.872340 (2350 4225);
PAINT GREEN (2350 4225);
DISPLAY INVISIBLE (2350 4225);
FORCEPROP 2 LAST PATH I88
J 0
(2200 4425);
DISPLAY 1.021277 (2200 4425);
PAINT ORANGE (2200 4425);
DISPLAY INVISIBLE (2200 4425);
FORCEADD ADM809..1
(400 3100);
FORCEPROP 1 LAST POWER_GROUP GND=GND;
J 0
(250 2750);
DISPLAY 0.617021 (250 2750);
PAINT ORANGE (250 2750);
FORCEPROP 1 LAST PART_NUMBER D23047-001
J 0
(255 2805);
DISPLAY 0.617021 (255 2805);
PAINT BLUE (255 2805);
FORCEPROP 2 LASTPIN (600 3000) $PN 2
J 0
(610 3010);
DISPLAY 0.617021 (610 3010);
PAINT MONO (610 3010);
FORCEPROP 2 LASTPIN (200 3150) $PN 3
J 2
(190 3160);
DISPLAY 0.617021 (190 3160);
PAINT MONO (190 3160);
FORCEPROP 1 LAST MATERIAL IC
J 0
(255 3318);
DISPLAY 0.617021 (255 3318);
PAINT SKYBLUE (255 3318);
FORCEPROP 1 LAST LOCATION U8E2
J 0
(255 3359);
DISPLAY 0.617021 (255 3359);
PAINT AQUA (255 3359);
FORCEPROP 2 LAST ROOM V_SUPER
J 0
(275 3400);
DISPLAY 1.021277 (275 3400);
PAINT ORANGE (275 3400);
DISPLAY INVISIBLE (275 3400);
FORCEPROP 2 LAST CDS_LOCATION U8E2
J 0
(255 3359);
DISPLAY 0.617021 (255 3359);
PAINT AQUA (255 3359);
DISPLAY INVISIBLE (255 3359);
FORCEPROP 2 LAST $SEC 1
J 0
(275 3400);
PAINT MONO (275 3400);
DISPLAY INVISIBLE (275 3400);
FORCEPROP 2 LAST CDS_SEC 1
J 0
(275 3400);
PAINT MONO (275 3400);
DISPLAY INVISIBLE (275 3400);
FORCEPROP 2 LAST CDS_LIB mstr_analog
J 0
(400 3100);
PAINT MONO (400 3100);
DISPLAY INVISIBLE (400 3100);
FORCEPROP 1 LAST PACK_TYPE SMLF
J 0
(255 3400);
DISPLAY 0.872340 (255 3400);
PAINT SKYBLUE (255 3400);
DISPLAY INVISIBLE (255 3400);
FORCEPROP 1 LAST PATH I89
J 0
(655 3310);
DISPLAY 0.872340 (655 3310);
PAINT PURPLE (655 3310);
DISPLAY INVISIBLE (655 3310);
FORCEADD RES..1
(1200 3000);
FORCEPROP 1 LAST WATTAGE 1/16W
J 2
(1175 2850);
DISPLAY 0.617021 (1175 2850);
PAINT SKYBLUE (1175 2850);
FORCEPROP 1 LAST VALUE 22.1
J 2
(1175 2900);
DISPLAY 0.617021 (1175 2900);
PAINT SKYBLUE (1175 2900);
FORCEPROP 1 LASTPIN (1100 3000) $PN 1
J 0
(1112 3012);
DISPLAY 0.617021 (1112 3012);
PAINT ORANGE (1112 3012);
FORCEPROP 1 LAST MATERIAL CHIP
J 0
(1200 2850);
DISPLAY 0.617021 (1200 2850);
PAINT SKYBLUE (1200 2850);
FORCEPROP 1 LAST TOLERANCE 1.0%
J 0
(1200 2900);
DISPLAY 0.617021 (1200 2900);
PAINT SKYBLUE (1200 2900);
FORCEPROP 1 LASTPIN (1300 3000) $PN 2
J 0
(1262 3012);
DISPLAY 0.617021 (1262 3012);
PAINT ORANGE (1262 3012);
FORCEPROP 1 LAST PACK_TYPE 0402
J 0
(1450 2850);
DISPLAY 0.617021 (1450 2850);
PAINT SKYBLUE (1450 2850);
FORCEPROP 1 LAST LOCATION R8E7
J 0
(1150 3050);
DISPLAY 0.617021 (1150 3050);
PAINT AQUA (1150 3050);
FORCEPROP 1 LAST PART_NUMBER G21796-250
J 0
(1150 3100);
DISPLAY 0.617021 (1150 3100);
PAINT BLUE (1150 3100);
FORCEPROP 2 LAST CDS_LIB mstr_discrete
J 0
(1200 3000);
PAINT MONO (1200 3000);
DISPLAY INVISIBLE (1200 3000);
FORCEPROP 2 LAST CDS_LOCATION R8E7
J 0
(1150 3050);
DISPLAY 0.617021 (1150 3050);
PAINT AQUA (1150 3050);
DISPLAY INVISIBLE (1150 3050);
FORCEPROP 2 LAST SEC 1
J 0
(1150 3200);
PAINT MONO (1150 3200);
DISPLAY INVISIBLE (1150 3200);
FORCEPROP 2 LAST SEC_TYPE 0402
J 0
(1150 3200);
DISPLAY 1.021277 (1150 3200);
PAINT ORANGE (1150 3200);
DISPLAY INVISIBLE (1150 3200);
FORCEPROP 1 LAST PATH I90
J 0
(1150 3150);
DISPLAY 0.978723 (1150 3150);
PAINT WHITE (1150 3150);
DISPLAY INVISIBLE (1150 3150);
FORCEPROP 0 LAST ROOM V_SUPER
J 0
(1150 3200);
DISPLAY 1.021277 (1150 3200);
PAINT ORANGE (1150 3200);
DISPLAY INVISIBLE (1150 3200);
FORCEADD OFFPAGE..2
(1850 3000);
FORCEPROP 2 LAST $XR0 181 
J 0
(2039 3000);
DISPLAY 0.638298 (2039 3000);
PAINT MONO (2039 3000);
FORCEPROP 2 LAST $XR1 241 
J 0
(2159 3000);
DISPLAY 0.638298 (2159 3000);
PAINT MONO (2159 3000);
FORCEPROP 2 LASTPIN (1800 3000) SIG_NAME PWRGD_P12V_HSC_DLY
J 2
(1790 3010);
DISPLAY 0.617021 (1790 3010);
PAINT ORANGE (1790 3010);
FORCEPROP 2 LAST CDS_LIB mstr_standard
J 0
(1850 3000);
PAINT MONO (1850 3000);
DISPLAY INVISIBLE (1850 3000);
FORCEPROP 1 LAST COMMENT_BODY TRUE
J 0
(1805 2905);
DISPLAY 0.872340 (1805 2905);
PAINT GREEN (1805 2905);
DISPLAY INVISIBLE (1805 2905);
FORCEPROP 2 LAST PATH I91
J 0
(2025 3075);
DISPLAY 1.021277 (2025 3075);
PAINT ORANGE (2025 3075);
DISPLAY INVISIBLE (2025 3075);
FORCEPROP 1 LAST OFFPAGE TRUE
J 0
(2175 2875);
DISPLAY 0.872340 (2175 2875);
PAINT GREEN (2175 2875);
DISPLAY INVISIBLE (2175 2875);
FORCEADD CAP_A..1
(-300 2950);
FORCEPROP 1 LASTPIN (-300 3050) $PN 1
J 0
(-290 3030);
DISPLAY 0.617021 (-290 3030);
PAINT ORANGE (-290 3030);
FORCEPROP 1 LASTPIN (-300 2850) $PN 2
J 0
(-290 2830);
DISPLAY 0.617021 (-290 2830);
PAINT ORANGE (-290 2830);
FORCEPROP 1 LAST MATERIAL X7R
J 0
(-250 2850);
DISPLAY 0.617021 (-250 2850);
PAINT SKYBLUE (-250 2850);
FORCEPROP 1 LAST VOLTAGE 16V
J 0
(-250 2950);
DISPLAY 0.617021 (-250 2950);
PAINT SKYBLUE (-250 2950);
FORCEPROP 1 LAST PACK_TYPE 0402V
J 0
(-250 2750);
DISPLAY 0.617021 (-250 2750);
PAINT SKYBLUE (-250 2750);
FORCEPROP 1 LAST TOLERANCE 10%
J 0
(-250 2900);
DISPLAY 0.617021 (-250 2900);
PAINT SKYBLUE (-250 2900);
FORCEPROP 1 LAST VALUE 0.1UF
J 0
(-250 3000);
DISPLAY 0.617021 (-250 3000);
PAINT SKYBLUE (-250 3000);
FORCEPROP 1 LAST LOCATION C8E3
J 0
(-250 3050);
DISPLAY 0.617021 (-250 3050);
PAINT AQUA (-250 3050);
FORCEPROP 1 LAST PART_NUMBER A36096-030
J 0
(-250 2800);
DISPLAY 0.617021 (-250 2800);
PAINT BLUE (-250 2800);
FORCEPROP 2 LAST CDS_LIB dev_discrete
J 0
(-300 2950);
PAINT ORANGE (-300 2950);
DISPLAY INVISIBLE (-300 2950);
FORCEPROP 2 LAST CDS_LOCATION C8E3
J 0
(-250 3050);
DISPLAY 0.617021 (-250 3050);
PAINT AQUA (-250 3050);
DISPLAY INVISIBLE (-250 3050);
FORCEPROP 2 LAST ROOM V_SUPER
J 0
(-250 3100);
DISPLAY 1.021277 (-250 3100);
PAINT ORANGE (-250 3100);
DISPLAY INVISIBLE (-250 3100);
FORCEPROP 1 LAST PATH I94
J 0
(-250 3100);
DISPLAY 0.978723 (-250 3100);
PAINT WHITE (-250 3100);
DISPLAY INVISIBLE (-250 3100);
FORCEPROP 2 LAST SEC_TYPE 0402V
J 0
(-250 3150);
DISPLAY 1.021277 (-250 3150);
PAINT ORANGE (-250 3150);
DISPLAY INVISIBLE (-250 3150);
FORCEPROP 2 LAST SEC 1
J 0
(-250 3150);
DISPLAY 0.680851 (-250 3150);
PAINT MONO (-250 3150);
DISPLAY INVISIBLE (-250 3150);
FORCEADD GND..1
(-300 2750);
FORCEPROP 3 LASTPIN (-300 2800) SIG_NAME GND\g
J 0
(-290 2810);
DISPLAY 0.659574 (-290 2810);
PAINT MONO (-290 2810);
DISPLAY INVISIBLE (-290 2810);
FORCEPROP 1 LAST BODY_TYPE PLUMBING
J 0
(-345 2707);
DISPLAY 0.340426 (-345 2707);
PAINT GREEN (-345 2707);
DISPLAY INVISIBLE (-345 2707);
FORCEPROP 1 LAST VOLTAGE 0.0V
J 0
(-345 2707);
DISPLAY 0.340426 (-345 2707);
PAINT SKYBLUE (-345 2707);
DISPLAY INVISIBLE (-345 2707);
FORCEPROP 2 LAST CDS_LIB mstr_symbols
J 0
(-300 2750);
PAINT MONO (-300 2750);
DISPLAY INVISIBLE (-300 2750);
FORCEPROP 1 LAST HDL_POWER GND
J 0
(-300 2900);
DISPLAY 0.872340 (-300 2900);
PAINT GREEN (-300 2900);
DISPLAY INVISIBLE (-300 2900);
FORCEPROP 1 LAST SIZE 1B
J 0
(-225 2700);
DISPLAY 0.872340 (-225 2700);
PAINT AQUA (-225 2700);
DISPLAY INVISIBLE (-225 2700);
FORCEPROP 1 LAST PATH I95
J 0
(-225 2750);
DISPLAY 0.872340 (-225 2750);
PAINT AQUA (-225 2750);
DISPLAY INVISIBLE (-225 2750);
FORCEADD OFFPAGE..1
(-900 3150);
FORCEPROP 2 LAST $XR0 199 
J 0
(-1152 3150);
DISPLAY 0.638298 (-1152 3150);
PAINT MONO (-1152 3150);
FORCEPROP 2 LASTPIN (-850 3150) SIG_NAME PWRGD_P12V_HSC
J 0
(-860 3160);
DISPLAY 0.617021 (-860 3160);
PAINT ORANGE (-860 3160);
FORCEPROP 1 LAST OFFPAGE TRUE
J 0
(-575 3025);
DISPLAY 0.872340 (-575 3025);
PAINT GREEN (-575 3025);
DISPLAY INVISIBLE (-575 3025);
FORCEPROP 1 LAST COMMENT_BODY TRUE
J 0
(-775 3050);
DISPLAY 0.872340 (-775 3050);
PAINT GREEN (-775 3050);
DISPLAY INVISIBLE (-775 3050);
FORCEPROP 2 LAST CDS_LIB mstr_standard
J 0
(-900 3150);
PAINT MONO (-900 3150);
DISPLAY INVISIBLE (-900 3150);
FORCEPROP 2 LAST PATH I96
J 0
(-850 3225);
DISPLAY 1.021277 (-850 3225);
PAINT ORANGE (-850 3225);
DISPLAY INVISIBLE (-850 3225);
FORCEADD P3V3_RTC_STBY..1
(-2200 4875);
FORCEPROP 3 LASTPIN (-2200 4825) SIG_NAME P3V3_RTC_STBY\g
J 0
(-2190 4835);
DISPLAY 0.659574 (-2190 4835);
PAINT MONO (-2190 4835);
DISPLAY INVISIBLE (-2190 4835);
FORCEPROP 1 LAST VOLTAGE 3.3V
J 0
(-2245 4832);
DISPLAY 0.340426 (-2245 4832);
PAINT SKYBLUE (-2245 4832);
DISPLAY INVISIBLE (-2245 4832);
FORCEPROP 1 LAST BODY_TYPE PLUMBING
J 0
(-2245 4832);
DISPLAY 0.340426 (-2245 4832);
PAINT GREEN (-2245 4832);
DISPLAY INVISIBLE (-2245 4832);
FORCEPROP 1 LAST HDL_POWER P3V3_RTC_STBY
J 1
(-2200 4925);
DISPLAY 0.872340 (-2200 4925);
PAINT GREEN (-2200 4925);
DISPLAY INVISIBLE (-2200 4925);
FORCEPROP 2 LAST ROOM SB_DECOUPLING
J 0
(-2200 4975);
DISPLAY 1.361702 (-2200 4975);
PAINT WHITE (-2200 4975);
DISPLAY INVISIBLE (-2200 4975);
FORCEPROP 1 LAST PATH I97
J 0
(-2150 4900);
DISPLAY 0.872340 (-2150 4900);
PAINT AQUA (-2150 4900);
DISPLAY INVISIBLE (-2150 4900);
FORCEPROP 2 LAST BOM_COST SB
J 0
(-2200 5025);
PAINT MONO (-2200 5025);
DISPLAY INVISIBLE (-2200 5025);
FORCEPROP 2 LAST CDS_LIB mstr_symbols
J 0
(-2200 4875);
PAINT ORANGE (-2200 4875);
DISPLAY INVISIBLE (-2200 4875);
FORCEADD OFFPAGE..1
(-900 3650);
FORCEPROP 2 LAST $XR0 240 
J 0
(-1152 3650);
DISPLAY 0.638298 (-1152 3650);
PAINT MONO (-1152 3650);
FORCEPROP 2 LAST $XR1 101 
J 0
(-1272 3650);
DISPLAY 0.638298 (-1272 3650);
PAINT MONO (-1272 3650);
FORCEPROP 2 LAST $XR2 189 
J 0
(-1392 3650);
DISPLAY 0.638298 (-1392 3650);
PAINT MONO (-1392 3650);
FORCEPROP 2 LAST $XR3 191 
J 0
(-1512 3650);
DISPLAY 0.638298 (-1512 3650);
PAINT MONO (-1512 3650);
FORCEPROP 2 LAST $XR4 237 
J 0
(-1632 3650);
DISPLAY 0.638298 (-1632 3650);
PAINT MONO (-1632 3650);
FORCEPROP 2 LAST $XR5 239 
J 0
(-1152 3614);
DISPLAY 0.638298 (-1152 3614);
PAINT MONO (-1152 3614);
FORCEPROP 2 LASTPIN (-850 3650) SIG_NAME PWRGD_P3V3_STBY
J 0
(-735 3685);
DISPLAY 0.617021 (-735 3685);
PAINT ORANGE (-735 3685);
FORCEPROP 1 LAST OFFPAGE TRUE
J 0
(-575 3525);
DISPLAY 0.872340 (-575 3525);
PAINT GREEN (-575 3525);
DISPLAY INVISIBLE (-575 3525);
FORCEPROP 1 LAST COMMENT_BODY TRUE
J 0
(-775 3550);
DISPLAY 0.872340 (-775 3550);
PAINT GREEN (-775 3550);
DISPLAY INVISIBLE (-775 3550);
FORCEPROP 2 LAST PATH I98
J 0
(-850 3725);
DISPLAY 1.021277 (-850 3725);
PAINT ORANGE (-850 3725);
DISPLAY INVISIBLE (-850 3725);
FORCEPROP 2 LAST CDS_LIB mstr_standard
J 0
(-900 3650);
PAINT MONO (-900 3650);
DISPLAY INVISIBLE (-900 3650);
FORCEADD DESIGN_NOTE..1
(500 5425);
FORCEPROP 0 LAST L1 FOR ADM1085:
J 0
(300 5275);
DISPLAY 1.021277 (300 5275);
PAINT ORANGE (300 5275);
FORCEPROP 0 LAST L3 TARGET POWER ON DELAY IS 225MS
J 0
(300 5075);
DISPLAY 1.021277 (300 5075);
PAINT ORANGE (300 5075);
FORCEPROP 0 LAST L2 NOMINAL TRIP POINT IS 8.97V
J 0
(300 5175);
DISPLAY 1.021277 (300 5175);
PAINT ORANGE (300 5175);
FORCEPROP 1 LAST COMMENT_BODY TRUE
J 0
(525 5525);
DISPLAY 0.978723 (525 5525);
PAINT ORANGE (525 5525);
DISPLAY INVISIBLE (525 5525);
FORCEPROP 2 LAST CDS_LIB mstr_symbols
J 0
(500 5425);
PAINT ORANGE (500 5425);
DISPLAY INVISIBLE (500 5425);
FORCEADD CAD_NOTE..1
(-2300 3950);
FORCEPROP 0 LAST L2 NEAR BATTERY HOLDER
J 0
(-2450 3775);
DISPLAY 0.617021 (-2450 3775);
PAINT WHITE (-2450 3775);
FORCEPROP 0 LAST L1 PLACE 1UF CLOSE TO DIODE
J 0
(-2450 3825);
DISPLAY 0.617021 (-2450 3825);
PAINT WHITE (-2450 3825);
FORCEPROP 2 LAST CDS_LIB mstr_symbols
J 0
(-2300 3950);
PAINT WHITE (-2300 3950);
DISPLAY INVISIBLE (-2300 3950);
FORCEPROP 1 LAST COMMENT_BODY TRUE
J 0
(-2275 4050);
DISPLAY 1.361702 (-2275 4050);
PAINT WHITE (-2275 4050);
DISPLAY INVISIBLE (-2275 4050);
FORCEADD INTEL_CORP_BPAGE..1
(2650 500);
FORCEPROP 1 LAST CDS_CON_LAST_MODIFIED Tue Dec 01 11:52:19 2015
J 0
(1225 825);
PAINT ORANGE (1225 825);
DISPLAY INVISIBLE (1225 825);
FORCEPROP 1 LAST CUSTOM_TXT_CDS <CURRENT_DESIGN_SHEET> OF <TOTAL_DESIGN_SHEETS>
J 0
(2150 525);
PAINT GREEN (2150 525);
FORCEPROP 1 LAST CUSTOM_TXT_CDS <CON_LAST_MODIFIED>
J 0
(725 850);
PAINT GREEN (725 850);
FORCEPROP 2 LAST CUSTOM_TXT_CDS <XR_PAGE_TITLE>
J 0
(-5240 5750);
DISPLAY 0.638298 (-5240 5750);
PAINT PINK (-5240 5750);
DISPLAY INVISIBLE (-5240 5750);
FORCEPROP 1 LAST SCH_TITLE BATTERY CIRCUIT/VOLTAGE SUPERVISORS
J 0
(-5300 550);
DISPLAY 1.212766 (-5300 550);
PAINT ORANGE (-5300 550);
FORCEPROP 1 LAST SCH_ADDRESS1 2200 Mission College Blvd.
J 0
(-1325 625);
DISPLAY 0.617021 (-1325 625);
PAINT GREEN (-1325 625);
FORCEPROP 1 LAST SCH_ADDRESS2 P.O. BOX 58119
J 0
(-1325 575);
DISPLAY 0.617021 (-1325 575);
PAINT GREEN (-1325 575);
FORCEPROP 1 LAST SCH_ADDRESS3 Santa Clara, CA 95052-8119
J 0
(-1325 525);
DISPLAY 0.617021 (-1325 525);
PAINT GREEN (-1325 525);
FORCEPROP 1 LAST SCH_REV 2.420
J 0
(2400 650);
DISPLAY 0.978723 (2400 650);
PAINT YELLOW (2400 650);
FORCEPROP 1 LAST SCH_DEPT BESD
J 1
(-1800 600);
DISPLAY 1.212766 (-1800 600);
PAINT YELLOW (-1800 600);
FORCEPROP 1 LAST SCH_NUMBER H4694802
J 0
(1350 650);
DISPLAY 1.212766 (1350 650);
PAINT YELLOW (1350 650);
FORCEPROP 2 LAST PAGE_BORDER TRUE
J 0
(-5240 5750);
DISPLAY 0.851064 (-5240 5750);
PAINT PINK (-5240 5750);
DISPLAY INVISIBLE (-5240 5750);
FORCEPROP 1 LAST COMMENT_BODY TRUE
J 0
(2662 512);
DISPLAY 0.468085 (2662 512);
PAINT GREEN (2662 512);
DISPLAY INVISIBLE (2662 512);
FORCEPROP 2 LAST CDS_LIB mstr_symbols
J 0
(2650 500);
PAINT MONO (2650 500);
DISPLAY INVISIBLE (2650 500);
FORCEPROP 2 LAST CDS_XR_PAGE_TITLE CR-196 : @BASEBOARD_FAB2_LIB.BASEBOARD_FAB2(SCH_1):PAGE196
J 0
(-5240 5750);
DISPLAY 0.638298 (-5240 5750);
PAINT PINK (-5240 5750);
DISPLAY INVISIBLE (-5240 5750);
FORCEADD DESIGN_NOTE..1
(-1950 3400);
FORCEPROP 0 LAST L1 ADM809S (2.93V TYPICAL) USED IN THESE 2 LOCATIONS.
J 0
(-2150 3250);
DISPLAY 1.021277 (-2150 3250);
PAINT ORANGE (-2150 3250);
FORCEPROP 2 LAST CDS_LIB mstr_symbols
J 0
(-1950 3400);
PAINT ORANGE (-1950 3400);
DISPLAY INVISIBLE (-1950 3400);
FORCEPROP 1 LAST COMMENT_BODY TRUE
J 0
(-1925 3500);
DISPLAY 0.978723 (-1925 3500);
PAINT ORANGE (-1925 3500);
DISPLAY INVISIBLE (-1925 3500);
FORCEADD DNS..2
(-20 4745);
PAINT RED (-20 4745);
FORCEPROP 1 LAST COMMENT_BODY TRUE
R 1
J 0
(55 4520);
DISPLAY 0.872340 (55 4520);
PAINT GREEN (55 4520);
DISPLAY INVISIBLE (55 4520);
FORCEPROP 2 LAST CDS_LIB mstr_misc
J 0
(-20 4745);
PAINT ORANGE (-20 4745);
DISPLAY INVISIBLE (-20 4745);
WIRE 16 -1 (-200 2150)(-150 2150);
WIRE 16 -1 (-150 2150)(-150 2050);
WIRE 16 -1 (-1000 1850)(-1000 1800);
WIRE 16 -1 (-1000 2700)(-1000 2400);
WIRE 16 -1 (-1000 2400)(-800 2400);
WIRE 16 -1 (-1000 2400)(-1000 2050);
WIRE 16 -1 (-1750 2000)(-1750 1950);
WIRE 16 -1 (-1750 2950)(-1750 2900);
WIRE 16 -1 (-1750 2300)(-1750 2250);
WIRE 16 -1 (-1750 1350)(-1750 1300);
WIRE 16 -1 (50 2800)(50 2750);
WIRE 16 -1 (750 1550)(750 1500);
WIRE 16 -1 (250 2250)(250 2100);
WIRE 16 -1 (750 2550)(750 2300);
WIRE 16 -1 (-2200 4400)(-2200 4300);
WIRE 16 -1 (-5050 4550)(-4950 4550);
WIRE 16 -1 (-5050 4550)(-5050 4300);
WIRE 16 -1 (-2850 4750)(-3250 4750);
WIRE 16 -1 (-3250 4750)(-3250 4925);
WIRE 16 -1 (-25 4850)(-25 4950);
WIRE 16 -1 (-525 4850)(-525 4950);
WIRE 16 -1 (1325 4750)(1325 4850);
WIRE 16 -1 (1075 4200)(1125 4200);
WIRE 16 -1 (1125 4200)(1125 4150);
WIRE 16 -1 (1225 3900)(1225 3950);
WIRE 16 -1 (275 4850)(275 4500);
WIRE 16 -1 (275 4500)(375 4500);
WIRE 16 -1 (275 4500)(275 4050);
WIRE 16 -1 (275 3800)(275 3850);
WIRE 16 -1 (-525 4150)(-525 4100);
WIRE 16 -1 (-300 1150)(-300 1100);
WIRE 16 -1 (-300 1400)(0 1400);
WIRE 16 -1 (-300 1450)(-300 1400);
WIRE 16 -1 (-300 1400)(-300 1350);
WIRE 16 -1 (-300 2850)(-300 2800);
WIRE 16 -1 (-2550 4650)(-2200 4650);
WIRE 16 -1 (-2200 4825)(-2200 4650);
WIRE 16 -1 (-2200 4600)(-2200 4650);
WIRE 16 2175 (-1750 5400)(-1750 3550);
WIRE 16 2175 (-5125 3550)(-1750 3550);
WIRE 16 -1 (925 3650)(1525 3650);
WIRE 16 -1 (1525 3650)(1525 4350);
WIRE 16 -1 (1975 4350)(1525 4350);
WIRE 16 -1 (1325 4350)(1525 4350);
WIRE 16 -1 (1325 4350)(1325 4550);
WIRE 16 -1 (1075 4350)(1325 4350);
WIRE 16 -1 (1225 4250)(1225 4150);
WIRE 16 -1 (1075 4250)(1225 4250);
FORCEPROP 2 LAST SIG_NAME A_ADM1085_CEXT
J 0
(1140 4260);
DISPLAY 0.617021 (1140 4260);
PAINT ORANGE (1140 4260);
FORCEPROP 2 LASTPROP $XRERR UNIQUE?
J 0
(900 4260);
DISPLAY 0.638298 (900 4260);
PAINT MONO (900 4260);
DISPLAY INVISIBLE (900 4260);
WIRE 16 -1 (1150 3400)(1350 3400);
WIRE 16 -1 (1350 3400)(1350 3000);
WIRE 16 -1 (1800 3000)(1350 3000);
WIRE 16 -1 (1350 3000)(1300 3000);
WIRE 16 -1 (1800 2400)(1450 2400);
WIRE 16 -1 (50 2550)(50 2400);
WIRE 16 -1 (1250 2400)(50 2400);
FORCEPROP 2 LAST SIG_NAME PWRGD_P12V_MAIN_R
J 0
(815 2410);
DISPLAY 0.617021 (815 2410);
PAINT ORANGE (815 2410);
FORCEPROP 2 LASTPROP $XRERR UNIQUE?
J 0
(575 2410);
DISPLAY 0.638298 (575 2410);
PAINT MONO (575 2410);
DISPLAY INVISIBLE (575 2410);
WIRE 16 -1 (-200 2400)(50 2400);
WIRE 16 -1 (600 3000)(1100 3000);
FORCEPROP 2 LAST SIG_NAME PWRGD_P12V_HSC_DLY_R
J 2
(1140 3010);
DISPLAY 0.617021 (1140 3010);
PAINT ORANGE (1140 3010);
FORCEPROP 2 LASTPROP $XRERR UNIQUE?
J 0
(900 3010);
DISPLAY 0.638298 (900 3010);
PAINT MONO (900 3010);
DISPLAY INVISIBLE (900 3010);
WIRE 16 -1 (750 2100)(750 2000);
WIRE 16 -1 (750 2000)(1250 2000);
FORCEPROP 2 LAST SIG_NAME PWRGD_P5V_R
J 0
(990 2010);
DISPLAY 0.617021 (990 2010);
PAINT ORANGE (990 2010);
FORCEPROP 2 LASTPROP $XRERR UNIQUE?
J 0
(750 2010);
DISPLAY 0.638298 (750 2010);
PAINT MONO (750 2010);
DISPLAY INVISIBLE (750 2010);
WIRE 16 -1 (750 2000)(750 1950);
WIRE 16 -1 (1800 2000)(1450 2000);
WIRE 16 -1 (1800 1250)(1400 1250);
WIRE 16 -1 (400 1250)(1200 1250);
FORCEPROP 2 LAST SIG_NAME PWRGD_P3V3_R1
J 0
(515 1260);
DISPLAY 0.617021 (515 1260);
PAINT ORANGE (515 1260);
FORCEPROP 2 LASTPROP $XRERR UNIQUE?
J 0
(275 1260);
DISPLAY 0.638298 (275 1260);
PAINT MONO (275 1260);
DISPLAY INVISIBLE (275 1260);
WIRE 16 -1 (250 1900)(250 1650);
WIRE 16 -1 (250 1650)(550 1650);
WIRE 16 -1 (0 1650)(250 1650);
WIRE 16 -1 (0 2300)(0 1650);
FORCEPROP 2 LAST SIG_NAME PWRGD_P5V_N
J 0
(290 1660);
DISPLAY 0.617021 (290 1660);
PAINT ORANGE (290 1660);
FORCEPROP 2 LASTPROP $XRERR UNIQUE?
J 0
(50 1660);
DISPLAY 0.638298 (50 1660);
PAINT MONO (50 1660);
DISPLAY INVISIBLE (50 1660);
WIRE 16 -1 (-200 2300)(0 2300);
WIRE 16 -1 (950 3400)(-50 3400);
WIRE 16 -1 (-50 3400)(-50 3150);
WIRE 16 -1 (-50 3150)(200 3150);
WIRE 16 -1 (-300 3150)(-50 3150);
WIRE 16 -1 (-850 3150)(-300 3150);
WIRE 16 -1 (-300 3150)(-300 3050);
WIRE 16 -1 (-525 4650)(-525 4450);
WIRE 16 -1 (-525 4450)(375 4450);
FORCEPROP 2 LAST SIG_NAME VSENSE_P12V_ADM1085
J 0
(-485 4460);
DISPLAY 0.617021 (-485 4460);
PAINT ORANGE (-485 4460);
FORCEPROP 2 LASTPROP $XRERR UNIQUE?
J 0
(-725 4460);
DISPLAY 0.638298 (-725 4460);
PAINT MONO (-725 4460);
DISPLAY INVISIBLE (-725 4460);
WIRE 16 -1 (-525 4350)(-525 4450);
WIRE 16 -1 (-25 3650)(725 3650);
WIRE 16 -1 (-25 3650)(-25 4350);
WIRE 16 -1 (-850 3650)(-25 3650);
WIRE 16 -1 (-25 4350)(375 4350);
WIRE 16 -1 (-25 4650)(-25 4350);
WIRE 16 -1 (-2850 4300)(-3250 4300);
FORCEPROP 0 LAST VOLTAGE +3 V
J 0
(-3175 4375);
PAINT SKYBLUE (-3175 4375);
DISPLAY INVISIBLE (-3175 4375);
FORCEPROP 2 LAST SIG_NAME A_P3V_BAT_R
J 0
(-3185 4310);
DISPLAY 0.617021 (-3185 4310);
PAINT ORANGE (-3185 4310);
WIRE 16 -1 (-3250 4550)(-3250 4300);
WIRE 16 -1 (-3250 4550)(-2850 4550);
WIRE 16 -1 (-3550 4550)(-3250 4550);
FORCEPROP 0 LAST CDS_PHYS_NET_NAME P3V_BAT_R
J 0
(-3350 4625);
DISPLAY 1.148936 (-3350 4625);
PAINT ORANGE (-3350 4625);
DISPLAY INVISIBLE (-3350 4625);
WIRE 16 -1 (-1150 2150)(-800 2150);
WIRE 16 -1 (-1150 1650)(-1150 2150);
WIRE 16 -1 (-1750 1650)(-1150 1650);
FORCEPROP 2 LAST SIG_NAME A_PG_P5V
J 0
(-1460 1660);
DISPLAY 0.617021 (-1460 1660);
PAINT ORANGE (-1460 1660);
FORCEPROP 2 LASTPROP $XRERR UNIQUE?
J 0
(-1700 1660);
DISPLAY 0.638298 (-1700 1660);
PAINT MONO (-1700 1660);
DISPLAY INVISIBLE (-1700 1660);
WIRE 16 -1 (-1750 1750)(-1750 1650);
WIRE 16 -1 (-1750 1650)(-1750 1550);
WIRE 16 -1 (-1150 2250)(-800 2250);
WIRE 16 -1 (-1150 2600)(-1150 2250);
WIRE 16 -1 (-1750 2600)(-1150 2600);
FORCEPROP 2 LAST SIG_NAME A_PG_P12V_MAIN
J 0
(-1460 2610);
DISPLAY 0.617021 (-1460 2610);
PAINT ORANGE (-1460 2610);
FORCEPROP 2 LASTPROP $XRERR UNIQUE?
J 0
(-1700 2610);
DISPLAY 0.638298 (-1700 2610);
PAINT MONO (-1700 2610);
DISPLAY INVISIBLE (-1700 2610);
WIRE 16 -1 (-1750 2700)(-1750 2600);
WIRE 16 -1 (-1750 2600)(-1750 2500);
WIRE 16 -1 (-4650 4600)(-4525 4600);
WIRE 16 -1 (-4525 4550)(-4525 4600);
WIRE 16 -1 (-4525 4550)(-3750 4550);
FORCEPROP 0 LAST CDS_PHYS_NET_NAME P3V_BAT_SOURCE
J 0
(-4200 4625);
DISPLAY 1.148936 (-4200 4625);
PAINT ORANGE (-4200 4625);
DISPLAY INVISIBLE (-4200 4625);
FORCEPROP 0 LAST VOLTAGE +3 V
J 0
(-4200 4675);
PAINT SKYBLUE (-4200 4675);
DISPLAY INVISIBLE (-4200 4675);
FORCEPROP 2 LAST SIG_NAME P3V_BAT_SOURCE
J 0
(-4410 4560);
DISPLAY 0.617021 (-4410 4560);
PAINT ORANGE (-4410 4560);
FORCEPROP 2 LASTPROP $XRERR UNIQUE?
J 0
(-4650 4560);
DISPLAY 0.638298 (-4650 4560);
PAINT MONO (-4650 4560);
DISPLAY INVISIBLE (-4650 4560);
WIRE 16 -1 (-4525 4500)(-4525 4550);
WIRE 16 -1 (-4650 4500)(-4525 4500);
DOT 1 (1325 4350);
DOT 1 (1525 4350);
DOT 1 (275 4500);
DOT 1 (1350 3000);
DOT 1 (50 2400);
DOT 1 (750 2000);
DOT 1 (250 1650);
DOT 1 (-25 4350);
DOT 1 (-525 4450);
DOT 1 (-2200 4650);
DOT 1 (-3250 4550);
DOT 1 (-25 3650);
DOT 1 (-50 3150);
DOT 1 (-300 3150);
DOT 1 (-1000 2400);
DOT 1 (-1750 2600);
DOT 1 (-300 1400);
DOT 1 (-1750 1650);
DOT 1 (-4525 4550);
FORCENOTE
ROOM = V_SUPER
(-450 900) 0;
DISPLAY LEFT (-450 900);
DISPLAY 1.021277 (-450 900);
PAINT PURPLE (-450 900);
FORCENOTE
BATTERY
(-3425 5250) 0;
DISPLAY LEFT (-3425 5250);
DISPLAY 0.617021 (-3425 5250);
PAINT PURPLE (-3425 5250);
FORCENOTE
COIN TYPE BATTERY
(-4550 4075) 0;
DISPLAY LEFT (-4550 4075);
DISPLAY 0.617021 (-4550 4075);
PAINT PURPLE (-4550 4075);
QUIT
